M48
INCH,TZ
T01C.012
T02C.016
T03C.14
T04C.157
T05C.073
T06C.086
T07C.091
T08C.146
;LEADER: 12 
;HEADER: 
;CODE  : ASCII 
;FILE  : 12432-1-1-8.drl for board 12432-1.brd ... layers TOP and BOTTOM
;T01 Holesize 1. = 12.000000 Tolerance = +0.000000/-0.000000 PLATED MILS Quantity = 1279
;T02 Holesize 2. = 16.000000 Tolerance = +0.000000/-0.000000 PLATED MILS Quantity = 4193
;T03 Holesize 3. = 140.000000 Tolerance = +0.000000/-0.000000 PLATED MILS Quantity = 11
;T04 Holesize 4. = 157.000000 Tolerance = +0.000000/-0.000000 PLATED MILS Quantity = 2
;T05 Holesize 5. = 73.000000 Tolerance = +0.000000/-0.000000 NON_PLATED MILS Quantity = 30
;T06 Holesize 6. = 86.000000 Tolerance = +0.000000/-0.000000 NON_PLATED MILS Quantity = 5
;T07 Holesize 7. = 91.000000 Tolerance = +0.000000/-0.000000 NON_PLATED MILS Quantity = 8
;T08 Holesize 8. = 146.000000 Tolerance = +0.000000/-0.000000 NON_PLATED MILS Quantity = 2
%
G90
T01
X41999Y200050
X23399Y373931
X28100Y374000
X23499Y381831
X29599Y382884
X26299Y383854
Y387629
X29699Y388484
X23399Y389679
X23499Y397579
X29999Y398684
X26299Y399601
Y403376
X29899Y404384
X45800Y405200
X23799Y405684
X35900Y412600
X28900Y417800
X29365Y421169
X26399Y423322
X26524Y426720
X23399Y429051
X28672Y429356
X28800Y436700
X23499Y436951
X26492Y439350
X26599Y442749
X23399Y444799
X28700Y445700
Y451900
X23499Y452699
X26899Y454850
X26799Y458497
X23399Y460547
X29500Y460800
X26486Y462648
X26499Y466250
X23499Y468447
X23399Y476295
X26299Y478404
X26515Y481798
X23499Y484195
X23399Y492043
X28664Y499429
X23499Y499943
X26399Y501966
Y505741
X23399Y507791
X28600Y508500
X38400Y514955
X23499Y515691
X36499Y517775
Y521550
X23399Y523539
X35338Y524746
X26599Y525648
Y529302
X23499Y531439
X26691Y532701
X27199Y539600
X22800
X26199Y547176
X42867Y548450
X46299Y552950
X39217Y554750
X43099Y555850
X29999Y557150
X33307Y557938
X49799Y559150
X33699Y561850
X22999Y565550
X36499Y566350
X42599Y567850
X25581Y567763
X27699Y573750
X44959Y575756
X22699Y577950
X47543Y578340
X28000Y578500
X22978Y588571
X28808Y593150
X55499Y595650
X28700Y596549
X32200Y603710
X31598Y607102
X45701Y607700
X42202Y608195
X23999Y609250
X47626Y611300
X41400Y611500
X26800
X37999Y611550
X26869Y616861
X23499Y618053
X34976Y619250
X27499Y620203
Y623857
X30712Y624971
X42709Y625607
X23799Y625950
X39600Y626984
X47101Y632355
X23499Y633801
X38300Y633800
X57800Y634300
X52500Y635000
X29819Y634951
X41500Y635000
X26568Y635950
Y639604
X29999Y640550
X23399Y641649
X44900Y642800
X41500
X48999Y642900
X23499Y649549
X30999Y650550
X26737Y651957
X30999Y656250
X26999Y656550
X23725Y657471
X23499Y665297
X27687Y667447
Y671101
X23699Y673150
X23499Y681045
X27700Y682700
X23999Y689050
X29999Y694550
X25999Y694870
X50410Y695801
X50300Y699200
X27299Y783550
X35300Y789375
X45100Y793100
X35559Y795112
X37416Y799033
X44046Y799554
X56281Y801350
X32800Y803050
X46887Y803413
X51100Y806300
X37216Y807951
X37099Y811350
X49900Y813200
X31699Y814350
X26299Y815050
X54074Y815750
X46700Y820100
X39649Y822000
X46576Y832951
X50399Y836250
X29299Y836901
X58699Y837250
X40400Y840792
X48346Y844529
X22500Y853700
X29600Y854000
X25000Y858100
X26662Y861550
X23299Y863050
X20400Y1048300
X20999Y1320550
Y1352050
X23700Y1354600
X25000Y1357742
X22999Y1366050
X25558Y1368447
X25507Y1372045
X22851Y1374169
X23499Y1381550
X27499Y1387550
X32333Y1389383
X24499Y1389663
X28499Y1391050
X32550Y1392777
X30500Y1395500
X32451Y1411468
X28999Y1411550
X23999Y1413550
X33321Y1414755
X29786Y1414858
X23499Y1421550
X23999Y1429050
X27999Y1430050
X33206Y1432352
X30499Y1434550
X22999Y1437050
X30999Y1438050
X27099Y1444350
X23499Y1445050
X36198Y1446749
X28697Y1448296
X32094Y1448448
X22999Y1453050
X29069Y1459379
X23499Y1460550
X36791Y1460866
X30378Y1462518
X33915Y1462681
X23028Y1468579
X23599Y1476350
X28999Y1478050
X34465Y1481683
X30999Y1482050
X23277Y1484050
X32520Y1485092
X24499Y1492050
X36999Y1494550
X27499Y1495050
X30499Y1497550
X34099
X22999Y1500050
X23799Y1508050
X30115Y1511900
X33512Y1512051
X35999Y1514550
X29765Y1515282
X22999Y1515550
X31999Y1517846
Y1521500
X35245Y1522512
X24199Y1523700
X24423Y1527123
X37999Y1530900
X29631Y1533063
X38500Y1534600
X26705Y1534795
X32099Y1535550
X30199Y1545450
X44697Y1546793
X25247Y1546912
X44299Y1550950
X34896Y1555730
X36340Y1558809
X24323Y1559950
X25521Y1563350
X31149Y1568300
X24999Y1569550
X38208Y1569841
X30520Y1572049
X27123Y1572205
X23608Y1572653
X39000Y1573500
X22699Y1594224
X31099Y1595350
X34999
X33599Y1600200
X42199Y1601050
X23499Y1602050
Y1610050
X26999Y1610550
X32299Y1613524
X28899
X34884Y1615734
X23499Y1618050
X22999Y1626050
X32663Y1628181
X29499Y1630050
X34816Y1630953
X32199Y1633124
X23499Y1634050
X23415Y1641634
X26785Y1642089
X29626Y1645002
X33026Y1645051
X32989Y1648451
X23999Y1649550
X27499Y1657050
X23499
X28600Y1661039
X31999Y1661127
X34699Y1663300
X22999Y1665550
X29100Y1669500
X32494Y1669706
X32700Y1673300
X22864Y1673550
X24244Y1681868
X30500Y1697500
X47400Y1721700
X45877Y1724823
Y1728477
X47717Y1731337
X47000Y1737100
X43600
X42000Y1740100
X47800Y1740500
X41200Y1747050
X39900Y1751200
X42275Y1754000
X45799Y1757650
X47440Y1761391
X47400Y1765250
X43925Y1767890
X47604Y1769005
X45782Y1771877
X47499Y1775350
X46999Y1779550
X43751Y1780559
X39324Y1780623
X46199Y1783050
X35675Y1783450
X38094Y1785840
X30274Y1787238
X37699Y1789850
X31811Y1790271
X48049Y1791450
X42199Y1792250
X37574Y1794050
X46799Y1794900
X40478Y1795820
X32099Y1797150
X47899Y1798650
X38878Y1799571
X34599Y1805123
X35876Y1812350
X34129Y1815267
X29899Y1821050
X34099Y1822850
X26099Y1824950
X36532Y1825352
X28550Y1828153
X36399Y1828750
X28123Y1831527
X39699Y1833850
X43099
X46499Y1836550
X22099Y1836609
X47166Y1839884
X25999Y1842550
X29599Y1844350
X57999Y1891050
X48499Y1897050
X42499Y1902550
X28799Y1919060
X26765Y1921945
X23030Y1922038
X14999Y1936050
X8499Y1937550
X14999Y1940050
X44399Y1942250
X15099Y1944050
X53999Y1946650
X50299
X46565Y1946703
X34799Y1946750
X42532Y1946783
X38703Y1946754
X5303Y1947050
X44368Y1951450
X11703Y1951946
X25499Y1956050
X32999Y1960555
X17499Y1961050
X43462Y1961160
X50499Y1961550
X45999Y1971450
X31799Y1979050
X97999Y1843050
X60449Y1842550
X80999Y1836550
X90000Y1827900
X93500
X96600Y1826000
X61009Y1822340
X80099Y1817250
X86649Y1817100
X85599Y1797350
X101399Y1784700
X74400Y1778100
X99199Y1761899
X110099Y1759875
X89499Y1753575
X99999
X85341Y1752245
X85194Y1748848
X89306Y1746856
X106999Y1746290
X109499Y1743550
X109399Y1739550
X107499Y1736550
X112562Y1720613
X92479Y1718176
X112753Y1716613
X109499Y1712213
X117249Y1712090
X104999Y1708963
X92873Y1708176
X117499Y1706050
X93999Y1703050
X118499Y1694050
X74500Y1692000
X78100Y1688189
X92900Y1678176
X95499Y1665418
X74800Y1584700
X74400Y1574800
X80400Y1571766
X82329Y1568117
X78600Y1561900
X75000Y1561800
X85600Y1561500
X89373Y1561073
X96999Y1558050
X82429Y1555500
X79000
X97499Y1554550
X96200Y1550100
X100000Y1546650
X83932Y1544705
X80043Y1544691
X99899Y1539850
X90324Y1538800
X100800Y1536450
X98144Y1534309
X98599Y1491350
X100499Y1479650
X100699Y1471050
X105099Y1459150
X106999Y1454450
X107999Y1448050
X104999Y1444941
X104935Y1440634
X107328Y1438218
X114499Y1432050
X76000Y1431100
X117390Y1429976
Y1426201
X119507Y1423540
X97000Y1377600
X97229Y1373337
X110499Y1365050
X112999Y1361550
X112440Y1358196
X77758Y1357742
X109999Y1355050
X113500Y1352000
X101500
X113500Y1348154
X102350
X89999Y1348050
X86890Y1346635
X102350Y1344500
X113500
X86890Y1342860
X102000Y1341000
X113000
X91279Y1340642
X107500Y1340500
X119499Y1339050
X86165
X109228Y1337090
Y1333315
X107228Y1330552
X116499Y1328013
X102700Y1321363
X78779Y1312664
X111499Y1311800
X107999Y1307713
X78779Y1302664
X119399Y1298113
X101399Y1292550
X116999Y1288050
X78613Y1282664
X78499Y1273550
X101541Y1262607
X103686Y1223863
X118999Y1219050
X103999Y1216863
X114999Y1210363
X106162Y1205702
X76999Y1196550
X102900Y1196050
X106999Y1194550
X74399Y1111550
X79899Y1104550
X112999Y1103740
X116249Y1102550
X108999Y1102050
X74500Y1097550
X80000Y1090500
X105999Y1085800
X105499Y1080550
X117499Y1079300
X106718Y1076050
X101499Y1072550
X105600Y1069500
X116700Y1063500
X112699Y1058974
X65486Y1031515
X66499Y1025050
X63273Y1023974
X72000Y1013400
X75500Y1012261
X88000Y1008500
X80699Y1004450
Y1000450
X92600Y996100
X90000Y993100
X107400Y992900
X107300Y986000
X104600Y980500
X102100Y968500
X99000Y965000
X108200Y963600
X89499Y942850
X85999Y940429
X86399Y937050
X89469Y935588
X106749Y934367
X108845Y931657
X109099Y928250
X108441Y924705
X94999Y901550
X92499Y876550
X92999Y868550
X74220Y854150
X76540Y850938
X72362Y849550
X75500Y847700
X69499Y842950
X63499Y843050
X98700Y842600
X68860Y838706
X110499Y834550
X98000Y833500
X90500Y831500
X90000Y826000
X98700Y822550
X62405Y820300
X65500Y817700
X80500Y817000
X89000Y816500
X111100Y813400
X111207Y810001
X111089Y806603
X110800Y803100
X111200Y799450
X110700Y795700
X110500Y790200
X81999Y668050
X76999Y664550
X80499
X74499Y662050
X78499Y654050
X82499Y627050
X81251Y619251
Y607249
X107000Y604800
X105100Y600000
X60076Y595777
X68000Y546500
X72500Y545000
X109400Y543200
X106000
X63499Y538550
X88999Y538050
X59999Y537550
X86199Y536025
X60003Y534150
X63499Y533050
X86199Y532250
X104502Y530552
X83700Y529500
X107526Y528996
X65599Y514250
X98900Y513400
X95500
X93200Y510500
X96900Y510000
X77499Y502550
X107499Y497050
X77999Y493050
X66299Y490784
X63067Y489616
X62978Y486217
X66299Y485484
X66199Y475184
X62497Y474346
X62503Y470946
X66199Y469884
X77499Y469550
X65000Y455500
X61400Y452600
X65999Y216050
X89800Y208550
X95350Y204550
X114900Y177900
X89603Y132629
X111790Y132259
X86899Y130567
X115876Y130050
X86599Y126750
X115876Y125973
X112999Y124050
X92999Y96128
X97499Y90050
X92999Y86128
X74499Y84050
Y80650
X78700Y74200
X74999Y74050
X78700Y70700
X74999Y70550
X92900Y66128
X93999Y58550
X174999Y79050
X178999
X175999Y82428
X175499Y86572
X176399Y94872
X169999Y129050
X173499Y149050
X152499Y149550
X127999Y157050
X173500Y166315
X149400Y166400
X154200Y168500
X149999Y239729
Y243504
X147099Y245350
X124999Y246050
X122799Y249150
X122397Y252688
X123378Y255944
X157440Y283924
Y303924
Y313924
X141499Y423050
X153459Y427494
X141499Y427550
X165699Y428050
X154101Y445550
X159600Y446399
X173100Y483100
X172499Y491053
X176799Y493850
X171722Y513827
X163549Y517100
X135499Y517550
X152000Y520813
X163449Y521650
X138999Y524213
X168453Y527949
X149000Y537500
X150750Y540416
X150500Y545000
X137899Y545451
X160932Y549468
X138416Y553500
X156500Y554000
X140940Y561800
X141300Y565900
X157000Y573851
X160824Y577000
X125499Y635550
X128725Y636626
X125499Y638950
X161000Y639100
X128479Y640589
X124999Y643050
X141773Y643013
X131400Y644600
X144238Y645356
X127999Y645550
X134300Y646400
X144238Y649131
X140499Y649350
X158885Y679436
Y689436
X141500Y711000
X158385Y719436
X159500Y814700
X165499Y815550
X172660Y815731
X169106Y815865
X153500Y834600
X154799Y838050
X174199Y841050
X153499Y918550
X172500Y919294
X160399Y922850
X172000Y931600
X171100Y935000
X163500Y937100
X171000Y939500
X170250Y948500
X152500Y960000
X172000Y961000
X154749Y968249
Y979149
X124100Y1047100
X123999Y1050650
X120100Y1053200
X123999Y1054050
X121100Y1075300
X140800Y1076300
X124423Y1077523
X137481Y1077557
X124423Y1081177
X137477
X159000Y1083000
X121500Y1083600
X137100Y1084800
X164700Y1085400
X125900Y1091282
X120749Y1093990
X132499Y1094550
X123999Y1102550
X157700Y1114948
X138600Y1124600
X157600Y1124948
X130699Y1210653
X123970Y1221573
X179499Y1275550
X125999Y1315550
X149562Y1315987
X120507Y1317050
X142667Y1319218
X132999Y1319550
X147400Y1321600
X135850Y1322250
X120507Y1328096
X133475Y1331200
X143700Y1332500
X140000Y1332600
X148024Y1333525
X129000Y1356500
X138000Y1359025
X121000Y1364000
X125100Y1366000
X150338Y1453958
X139815Y1454438
X142999Y1456373
X142900Y1460000
X139235Y1460973
X127898Y1462441
X152499Y1462940
X123808Y1465050
X124290Y1469241
X123999Y1473050
X122199Y1476050
X157440Y1490460
Y1500460
Y1520460
Y1530460
X157400Y1596550
X160200Y1598500
X171999Y1662250
X165575Y1676975
X152633Y1677967
X169600Y1682300
X169100Y1685800
X177900Y1690400
X174250Y1694500
X133090Y1699959
X128749Y1703300
X122642Y1704243
X131999Y1710050
X135499Y1710150
X123749Y1711550
X150999Y1713550
X141500Y1715500
X141999Y1764550
X165900Y1790500
X161900Y1793400
X140999Y1859550
X137999Y1861497
Y1865151
X141101Y1866545
X123393Y1870859
X123592Y1874254
X135999Y1881550
X159421Y1925972
X213138Y1952703
X210999Y1942050
X220062Y1931113
X213562Y1926113
X231999Y1914050
X214999Y1909550
X232314Y1890513
X223436Y1890465
X227814Y1887513
X231800Y1887100
X218100Y1886400
X236225Y1883125
X229800Y1875700
X194049Y1792600
X201499Y1781050
X181100Y1682700
X179999Y1655887
X193500Y1647000
X232650Y1493450
X224750Y1483950
X233700Y1481600
X229025Y1471576
X194700Y1385700
X180500Y1369900
X181000Y1365500
X199149Y1362900
X226800Y1093400
X221300Y1083238
X229800Y1073600
X221800Y1069300
X233500Y1066100
X198924Y975975
X215499Y905550
X229562Y904113
X200799Y896600
X211750Y894600
X200539Y890300
X200000Y818000
X236800Y765800
X228999Y765550
X218224Y765325
X230849Y726050
X213999Y725050
X216999Y686550
X238500Y680800
X193549Y575875
X183499Y556100
X199900Y554050
X182499Y532550
X220000Y516400
X187699Y492850
X188000Y484500
X233998Y357549
X239400Y357400
X224998Y357049
X213400Y355300
X231800Y318414
X214063Y318114
X213499Y283864
X225298Y281114
X239600Y278600
X218499Y190550
X197899Y165075
X188999Y120800
X233749Y110800
X207999Y109550
X223499Y108150
X237899Y107050
X205499Y105550
X213499Y104650
X201499Y104550
X186999Y99050
X210738Y82159
Y78459
X230749Y76300
X210685Y74725
X215138Y72559
X205938Y72528
X210605Y70692
X225499Y68550
X210634Y66863
X210638Y62959
X296099Y17100
X246499Y42550
X253999Y44050
X246999Y51550
Y60550
Y69550
X246499Y80550
Y86050
X282800Y87500
X291999Y94050
X297499Y97550
X245499Y100550
X247800Y269700
X250300Y275100
X250400Y283100
X253871Y291410
X293999Y293550
X252935Y319114
X298800Y333000
X284999Y338650
X281499Y338550
X294500Y339000
X246800Y677100
X249700Y682500
X249800Y689900
X254499Y697700
X252499Y726050
X279939Y728610
X277039Y740300
X298000Y743500
X292999Y743650
X285499Y745050
X282099
X241600Y765700
X242000Y1066000
X247500Y1085500
X255000Y1125700
X256000Y1133000
X282500Y1135000
X269500Y1135500
X251500Y1136700
X241000Y1469600
X295000Y1513000
X261999Y1516050
X276039Y1551300
X293700Y1553351
X289999Y1554650
X279999Y1556050
X283499
X291400Y1561500
X297800Y1561600
X249600Y1896800
X257499Y1911050
X249499Y1928050
X285499Y1930050
X240964Y1934113
X280689Y1942710
X284999Y1947691
X288709Y1948042
X264499Y1964050
X327100Y1966472
X315999Y1958550
X310499Y1957050
X329999Y1952273
X332103Y1948133
X342999Y1947409
X331622Y1944767
X342621Y1943409
X325221Y1927272
X313499Y1919050
X348499Y1762050
X353499Y1710450
X354000Y1584900
X349774Y1582900
X323999Y1577250
X310249Y1569800
X312999Y1566050
X324000Y1562500
X330300Y1561200
X354500Y1559500
X326500Y1550200
X314999Y1527550
X347324Y1524000
X345424Y1310050
X345499Y1096550
X340699Y1046086
X329499Y801550
X320499Y798050
X330540Y795509
X324959Y766750
X310999Y757050
X323249Y749010
X327749Y744050
X327999Y740550
X315999Y718950
X308999Y716450
X350499Y715050
Y597300
X344520Y406329
X321900Y364600
X313039Y352350
X301249Y346050
X326499Y337454
Y334054
X323400Y105200
X315800Y100500
X324800Y89400
X308999Y87050
X357503Y77043
X354999Y72050
X341499Y67110
Y63050
X358999Y61550
X343499Y60150
Y31650
X317000Y17300
X311400Y17100
X305099Y17000
X398799Y36152
X382339Y41610
X394199Y45050
X381999Y50150
Y53550
Y57050
X374499Y77550
X385999Y78050
X401499Y80550
X365499Y86550
X400499Y406329
X371999Y549300
X394649Y630600
X375999Y698550
X371500Y880600
X364499Y1099050
X372999Y1123550
X370149Y1320050
X402499Y1476850
X390999Y1514398
Y1517798
X366149Y1554050
X400999Y1575550
X377900Y1703800
X385499Y1735050
X644360Y1819137
X645549Y1815134
X659549Y1810634
X690249Y1805634
X707600Y1815600
X711652Y1822109
X711848Y1825504
X759114Y1957673
X764908Y1946592
X767999Y1945173
X771499Y1940050
Y1936550
X758499Y1893550
X755000Y1825000
X770999Y1820550
X733049Y1814134
X732549Y1806634
X733149Y1798634
X774500Y1788000
X758199Y1553650
X767936Y1540336
X771225Y1539474
X774577Y1533796
X774542Y1530050
X757999Y1484050
X758499Y1371050
X755600Y1149800
X768199Y1138590
X767083Y1134550
X779499Y1131050
X772499Y1130050
X771999Y1124550
X757499Y1079550
X752999Y746842
X757499Y745342
X762999Y734550
X769999Y733050
X766499Y732842
X771105Y722789
X760778Y345050
X768178Y333964
X772873Y326924
X772499Y323050
X770999Y302050
X777999Y296050
X763571Y295622
X770999Y295550
Y290050
X827499Y163550
X820749Y163850
X813249Y163800
X839249Y164050
X821999Y193116
X833576Y215432
X829917Y216200
X837999Y219550
X822100Y261700
X809940Y264940
X816700Y274300
X827500Y274500
X836500Y274950
X822100Y279500
X785499Y291050
X786978Y298529
X827499Y313424
X780499Y330050
X791499Y333050
X784499Y334050
X789999Y336550
X820600Y664300
X829800Y666650
X808660Y667540
X813200Y675900
X835150Y677650
X781999Y725550
X791999Y733050
X784939Y733550
X788999Y736050
X825800Y1072300
X807000Y1072900
X815400Y1078800
X825700Y1083100
X792154Y1135926
X784439Y1136550
X789499Y1138050
X803199Y1151850
X822100Y1466800
X809960Y1478040
X814700Y1486300
X836625Y1487400
X827700Y1487600
X784499Y1529050
X784577Y1535628
X793999Y1541050
X791499Y1543550
X804899Y1556950
X788000Y1788000
X821249Y1791250
X811000Y1793000
X812000Y1799500
X793000Y1803500
X795849Y1805500
X822499Y1815164
X791999Y1819050
X807000Y1822300
X803500Y1822708
X783499Y1827050
X822700Y1871100
X828500Y1877800
X810900Y1882440
X805900Y1887560
X782999Y1937050
X794499Y1941050
X800431Y1941193
X785939Y1946800
X834799Y1946950
X792499Y1949050
X802499Y1951550
X802099Y1961950
X872086Y1935972
Y1925972
X857099Y1917650
X863699Y1906450
X871921Y1905972
X871421Y1895972
X859314Y1891365
X854814Y1883550
X850099Y1871056
X853499Y1871036
X854480Y1867578
X849999Y1867550
X863788Y1866953
X866914Y1865615
Y1861840
X865501Y1858747
X854905Y1825583
X849375Y1824982
X851500Y1821400
X879700Y1786300
X879664Y1782213
X873800Y1733600
X886439Y1717600
X862800Y1712700
X889800Y1711500
X867523Y1542821
X867199Y1535150
X872086Y1530460
X871999Y1520460
X863699Y1501250
X871999Y1500460
X872086Y1490460
X858827Y1485696
X854327Y1477550
X848888Y1466402
X852288Y1466346
X852429Y1462948
X848861Y1462463
X874499Y1460550
X877853Y1459991
X878054Y1456450
X874986Y1454983
X866700Y1379796
X861849Y1376050
X866596Y1375796
X860799Y1358925
X864499Y1128750
X871499Y1124948
X872086Y1114948
X871999Y1094948
X872086Y1084948
X860133Y1084142
X852333Y1077716
X847233Y1061492
X850833Y1061441
X847355Y1058094
X851042Y1058047
X874733Y1055792
X877964Y1054485
X878233Y1051095
X874999Y1049550
X883083Y979183
X879708Y971892
X852696Y671197
X851172Y655432
X847772Y655370
X847493Y651981
X851197Y652032
X875270Y650059
X878596Y649348
Y645573
X874999Y644550
X879750Y570550
X879950Y565050
X868299Y336150
X867899Y321550
X886200Y313924
X886600Y303924
X868799Y294750
X865499Y288050
X871999Y283924
X842499Y280924
X858478Y274050
X872136Y273924
X854400Y264600
X851278Y249974
X847878Y250040
X847450Y246666
X850999Y246550
X874790Y244748
X878078Y243878
Y240103
X874928Y238822
X867500Y163924
X867576Y159924
X882499Y147050
X861999Y146550
X896999Y141550
X841499Y135550
X898999Y110550
Y99050
X897555Y90494
X928461Y75981
X928457Y79885
X943499Y82550
X928428Y83714
X923761Y85550
X932961Y85581
X928508Y87747
X928561Y91481
X901499Y92050
X928561Y95181
X958999Y96050
X902499Y110550
X926999Y115050
X916499
X938499Y115550
X930999
X934499Y118750
X937999Y122050
X926999
X946899Y122550
X910999Y124550
X907499Y131800
X916499Y172550
X939549Y175175
X902999Y556050
X922049Y574375
X900499Y962100
X922049Y978575
X900999Y979050
X921549Y1788475
X917499Y1796550
X989900Y1678800
X987200Y1675600
X974000Y1670700
X978000Y1668000
X984211Y1667500
X989000Y1663802
X977500Y1660500
X980800Y1659600
X988800Y1658300
X981500Y1653000
X967600Y1651100
X982050Y1649302
X971558Y1646500
X989502Y1646000
X965150Y1639500
X986400Y1639302
X969600Y1638300
X961702Y1636102
X987029Y1634075
X990425Y1633898
X981200Y1625800
X987100Y1624900
X981200Y1618002
X965999Y954550
X966499Y552050
X961499Y100050
Y93350
T02
X36000Y5604
X17600
X10000Y16500
X23499Y27050
X11499Y34050
X27799Y38450
X11999Y53550
X25799Y64050
X11999Y69050
Y88550
X28399Y94950
X11499Y106050
X34999Y108550
X11999Y124550
X27999Y131050
X11499Y142050
X27999Y145550
X11999Y161550
X27999Y163050
X11999Y177050
Y196550
X11499Y214050
X9499Y229050
X23999
Y243550
X8999Y246550
X23999Y261050
X9499Y266050
Y281550
Y301050
X8999Y318550
X15499Y328050
Y342550
Y360050
X37499Y714050
X36999Y719550
Y725050
X36499Y732550
Y740050
X26399Y750850
X14799Y751450
X8599Y751650
X39899Y754850
X27199Y764950
X39399Y768750
X10999Y774050
X17299Y773950
X28599Y775450
X26799Y874550
X8999Y889550
X26099Y891650
X8499Y907050
X25699Y916150
X8999Y926550
Y942050
X25099Y942150
X23899Y957950
X8999Y961550
X8499Y979050
X8999Y988550
X24799Y992250
X8499Y1006050
X33899Y1005950
X8999Y1025550
Y1041050
Y1060550
X21499Y1073250
X8499Y1078050
Y1089050
X21399Y1090850
X7999Y1106550
X8499Y1126050
Y1141550
Y1161050
X7999Y1178550
Y1192550
X7499Y1210050
X7999Y1229550
Y1245050
Y1264550
X7499Y1282050
X21799Y1282750
X21299Y1300250
X8799Y1302550
X8299Y1320050
X18099Y1343550
X9399Y1347350
X15399Y1708350
X7099Y1717750
X15299Y1723450
X7199Y1731450
X14899Y1736250
X15299Y1753250
X6099Y1753750
X31499Y1849750
X11299Y1850050
X23999Y1857950
X39399Y1864350
X27199Y1874350
X9099Y1881550
X34799Y1890050
X8499Y1979550
X11500Y1987000
X26500
X61500Y1987500
X79500
X44500Y1987000
X73499Y1982550
X65499
X55999
X58999Y1958050
X66499Y1957050
X73499
Y1945550
X62499Y1939550
X47499Y1930550
X62999Y1926050
X47499Y1915050
X62999Y1914550
X78999Y1904050
X78433Y1900010
X78999Y1896050
Y1891550
Y1887550
X45699Y1875550
X52999Y1871550
X57499Y1871050
X78529Y1788113
X77165Y1759550
X78999Y1602050
X74499
X78999Y1598050
X74499
X78999Y1593550
X74999
X76999Y1528050
Y1519050
X76499Y1512050
Y1507050
Y1503050
Y1498050
X77166Y1353400
X77165Y1327335
X67000Y1011500
X65799Y994050
X72799Y982950
X77499Y962152
X77002Y952079
X76711Y948089
X77499Y921550
X76399Y820450
X70100Y818900
X79299Y794150
X53999Y791000
X67999Y790400
X47999Y771550
X52499
X47999Y767550
X51999Y767050
X41999Y739550
X46499Y739050
Y735050
X41999
Y731050
X46499Y730550
X41999Y724550
X51499
X46499
X50999Y720050
X46499Y719550
X41499
X53210Y701486
X47800Y692800
X43499Y657550
X52333Y641295
X61099Y603236
X72599Y578236
X39999Y576550
X42299Y564150
X49555Y563550
X62055Y561550
X75999Y556640
X70800Y540300
X77165Y514650
X66099Y500950
X75300Y454100
X67300Y450200
X68899Y445450
X76099Y414250
X39999Y359550
X52199Y342350
X39999Y342050
Y327550
X51099Y300050
X42999Y275650
X75299Y261750
X48499Y260550
Y243050
Y228550
X41699Y183250
X52499Y162550
Y145050
X78165Y137116
X41399Y134150
X52499Y130550
X71015Y123666
X77165Y110799
X59499Y108050
Y90550
Y76050
X65499Y59050
X50999Y47750
X40999Y42050
X65499Y41550
X40999Y27550
X65499Y27050
X50999Y21150
X73900Y6200
X55700Y5900
X90900Y5800
X107000Y6000
X90899Y14850
X97800Y36000
X92900Y39700
X96900Y40400
X93000Y44900
X96999Y49550
X92999Y52050
X116400Y56000
X114800Y68500
X95814Y136065
X96184Y151065
X117500Y162300
X96184Y166065
X97999Y199050
X92899Y231450
X86899Y242750
X93199Y279650
X84899Y289250
X90899Y309550
X94199Y325550
X93499Y337450
X95499Y355450
X89899Y368350
X89999Y396450
X87599Y403950
X109499Y410250
X95399Y416350
X111299Y425850
X89099Y426150
X99399Y437450
X93500Y445300
X97999Y445550
X97699Y449850
X93199
X100500Y456700
X94500Y456800
X97699Y477050
X93499
X97699Y481550
X93499
X94499Y486550
X98999Y488050
X101500Y536500
X108599Y557236
X93100Y571640
X93599Y581236
X108900Y587600
X92599Y606236
X112200Y762200
X112000Y773000
X111299Y821050
X97800Y851800
X93808Y852063
X94001Y856895
X98001Y856950
X97499Y862050
X93299
X93900Y882400
X97900
X93690Y887139
X97700Y887400
X93499Y892050
X97499Y892550
X93499Y897152
X112999Y901150
X93000Y907165
X83988Y934028
X106500Y943000
X105300Y960300
X86700Y982100
X100999Y1096550
X105006Y1096866
X100999Y1101050
X104999
X106999Y1114960
X110999Y1118050
X114999
Y1122050
X110999
X114999Y1126050
X110999
X115200Y1130300
X110999Y1130550
X102999Y1188050
X111999
X100999Y1231032
X104999Y1231050
X117149Y1267550
X103499Y1305050
X93316Y1351000
X96000Y1369000
X96100Y1384650
X97300Y1564100
X81499Y1589050
X86999
X92499
X83499Y1594050
Y1598050
Y1602050
X90999Y1624550
X85999
X90999Y1628550
X85999
X91121Y1632549
X86299Y1632550
X118999Y1670550
X105749Y1712749
X84099Y1737150
X83599Y1744750
X117499Y1745050
X93499Y1759550
X94336Y1773113
X104417Y1791480
X104500Y1813400
X97999Y1815050
X116499Y1877550
X111499
Y1882550
X115999
X82999Y1887550
Y1891550
X83499Y1896050
X83999Y1900050
X83433Y1904010
X81499Y1915550
X98433Y1940510
X102433Y1940555
X103433Y1944510
X98999Y1944550
X83999Y1945050
X82499Y1957050
X92499Y1959050
X119499Y1972550
X108499Y1981750
X82999Y1982550
X91499Y1983050
X101699Y1983850
X115000Y1987000
X98000Y1987500
X146000
X128500
X119999Y1978550
X127499
X133499
X148499Y1977250
X126999Y1972550
X132999
X146899Y1961750
X159173Y1935972
X124999Y1912550
X129433Y1912510
X129999Y1908550
X124433Y1908510
X142499Y1905972
X141499Y1895972
X122999Y1889050
X127499
X122999Y1883050
X126999Y1882550
X159054Y1881800
X143490Y1855972
X159054Y1855050
X157999Y1840972
X158000Y1825400
X142144Y1801644
X157500Y1797400
X120299Y1796150
X126599Y1789650
X137999Y1747723
X129999Y1747050
X123499
X144499Y1745550
X128000Y1735000
X133000Y1734500
X139500Y1730500
X130499Y1730050
X144499Y1729550
X122499Y1672550
X126562Y1670613
X122499Y1668550
X120100Y1633100
X124999Y1633050
Y1629050
X119999
X124999Y1620050
Y1616050
X127200Y1569800
X122600Y1565000
X129100Y1564700
X159054Y1476200
X140799Y1435460
X157915Y1420460
X143199Y1412050
X156999Y1397750
X123500Y1360300
X145999Y1353050
X123938Y1267623
X120499Y1264550
X126499
X148486Y1230113
X144149
X120999Y1228550
X144149Y1226113
X148499
X121657Y1224604
X148499Y1222113
X144149
X142499Y1205550
X130999Y1198050
X143899Y1196750
X128400Y1188600
X120999Y1188050
X141499Y1185550
X150999Y1181150
X151499Y1173050
X144399Y1171150
X145900Y1163200
X151699Y1158550
X126400Y1138100
X133200Y1132100
X143200Y1116300
X134500Y1108100
X137900Y1103400
X139100Y1097100
X159055Y1070400
X151300Y1049300
X140864Y1044885
X159499Y1044579
X141234Y1029885
X158300Y1015000
X149499Y997650
X156499Y985950
X159186Y946117
X153299Y943750
X151999Y936550
X152499Y931550
X157499Y909050
Y904550
X159459Y896616
X155499Y896050
Y891050
X156499Y886950
X158114Y883290
X156499Y876050
Y870550
X155999Y863050
Y859050
X156999Y850050
X156499Y846050
X152499Y825050
Y820550
Y816050
Y810550
X139099Y707150
X131099Y700450
X159054Y665400
X152124Y651868
X152400Y643300
X140499Y626050
X143999Y605550
X140499Y600550
X140000Y587700
X154099Y529236
X147300Y526700
X147590Y521500
X145649Y509550
X136349Y509050
X153499Y502550
X148999
X136299Y499050
X140499
X134499Y488050
X139200Y484300
X135140Y478930
X154100Y476500
X135999Y472550
X149700Y471600
X130000Y452000
X128999Y445550
X133499Y445050
X127999Y429550
X122499Y427900
X127999Y425050
Y421050
X150699Y411050
X124899Y409050
X126099Y396150
X152499Y395950
X139399Y372350
X134699Y356050
X130099Y326150
X130799Y300250
X135399Y277050
X157740Y273924
X158999Y259800
X152808Y246341
X133000Y240500
X142688Y218861
X143110Y203861
X131799Y201950
X155999Y181050
X124300Y167800
X123499Y149050
X133999
X144499
X132999Y141550
X152999Y141050
X142999
X123499Y140050
X127999Y99550
X158499Y93550
Y88550
Y84050
Y79050
X129999Y78050
X156499Y66050
X141999Y65550
X127499Y65050
X129100Y55900
X157299Y5150
X189499Y4550
Y39150
X193999Y39900
X197999
X167499Y43550
X194499Y44050
X183499Y45550
X192499Y57550
X168499Y65550
X191999Y68050
X166499Y79050
Y83550
X166999Y88050
Y92550
Y97050
X169999Y103050
X165499Y106050
X176499Y140050
X163499
X167499Y149550
X160999
X190199Y178650
X177899Y199250
X191999Y221550
X166800Y240800
X185999Y250550
X181299Y267350
X187199Y359050
X167299Y369350
X181599Y396250
X168999Y413050
X188499Y413550
X179649Y438550
X183999
Y442550
X179999
X183999Y447050
X179999
X164600Y476700
X171300
X190499Y487550
X194999Y490050
X191199Y491550
X190499Y507513
X187499Y531613
Y536113
X188999Y541113
X193499
X193999Y545550
X188999Y545613
X193499Y549613
X188999
X181999Y609550
X162500Y623400
X181999Y624050
Y641550
X199199Y659150
X171999Y672450
X182599Y688350
X190399Y689050
X170799Y689150
X178899Y765250
X161999Y768050
X172599Y774250
X190699Y778350
X197099Y795050
X198199Y805950
X161999Y843550
X173899Y846550
X168499Y846713
X161999Y848050
X163999Y863050
X159999
X172099Y877450
X198499Y884113
X163499Y896550
X169299Y956350
X171499Y998650
X162499Y1023550
X163499Y1035050
X165600Y1057428
X169299Y1067150
X164999Y1075550
X168099Y1083550
X167999Y1092850
X199499Y1093850
X167499Y1118550
X167999Y1130550
X171599Y1139950
X163499Y1171650
X196499Y1196550
X180400Y1202800
X196499Y1215550
X181700Y1219900
X196499Y1224550
X196399Y1236650
X179800Y1244100
X195499Y1251050
X179500Y1262000
X195499Y1270050
Y1279050
X179999Y1292550
X175499
X179999Y1296613
X175823Y1297070
X179999Y1301550
X175499Y1302113
X179999Y1306050
X175499Y1306113
X195500Y1352500
X167499Y1389050
X178200Y1393400
X166799Y1409350
X180599Y1424050
X163499Y1433350
X180000Y1439500
X176599Y1447450
X165499Y1453550
X194200Y1457900
X172299Y1465850
X181500Y1479000
X166799Y1487450
X176299Y1500150
X195700Y1619100
X180000Y1619600
X195600Y1623700
X180299Y1626550
X179733Y1630590
X180299Y1634550
X199900Y1670600
X193499Y1674050
X181900Y1675300
X197600Y1694900
X195001Y1708150
X172499Y1714050
X162499Y1714113
X167499
X180701Y1716050
X195500Y1717000
X179701Y1724550
X195000Y1725500
X163499Y1726613
X172499
X167999
X165499Y1730613
X170499Y1731050
X180000Y1731000
X185999Y1746050
X199699Y1761450
X182299Y1801350
X173899Y1813250
X192100Y1813500
X168499Y1855550
X177599Y1866750
X167200Y1868000
X199599Y1879850
X168299
X181099Y1885850
X191599Y1891550
X163599Y1892050
X168699Y1957150
X190199Y1957650
X183999Y1968150
X199600Y1974900
X188199Y1978250
X163500Y1987500
X183000
X199000
X216999Y1987550
X236500Y1987500
X225199Y1978750
X209699
X221300Y1971200
X232999Y1971050
X227499
X238999Y1970550
X205499Y1968650
X226999Y1941050
X207199Y1892850
X212399Y1885850
X206999Y1867550
X224800Y1867000
X228999Y1856050
X204399Y1855450
X209999Y1825050
X215299Y1813950
X205199Y1801950
X238699Y1801850
X220799Y1791550
X221499Y1760950
X222499Y1743850
X237999Y1730550
X206900Y1726700
X222700Y1710100
X205200Y1708000
X201801Y1701450
X212000Y1701300
X235499Y1697050
X209901Y1691850
X220100Y1691700
X204400Y1688200
X216601Y1684350
X226800Y1684200
X213000Y1672500
X230600Y1670500
X237400Y1663800
X200600Y1663600
X211999Y1653550
X228999Y1637550
X239400Y1624300
X209200Y1624000
X218000Y1614300
X238300Y1575100
X224499Y1575050
X231499
X211999Y1574550
X217999
X211999Y1568550
X236999Y1535550
X212899
X230999
X202399Y1500750
X213399Y1500300
X208999Y1491250
X204999Y1472650
X238899Y1453750
X226300Y1447800
X230899Y1437350
X212400Y1433700
X227999Y1421550
X204699Y1418350
X217999Y1408850
X201000Y1408500
X230599Y1400250
X203199Y1393250
X217499Y1387450
X208049Y1385550
X234300Y1375700
X227399Y1363050
X213199Y1350050
X226599Y1340250
X207699Y1337950
X219099Y1325950
X239099Y1314150
X202899Y1291450
X202199Y1276850
X232799Y1276150
X216300Y1274800
X211499Y1267050
Y1258050
X222299Y1251850
X229899Y1250550
X211499Y1239050
X221599Y1237250
X234299Y1232650
X220999Y1224350
X212499Y1212550
X201600Y1205900
X232599Y1195750
X212499Y1184550
X223099Y1182750
X210199Y1173450
X204199Y1163850
X214499Y1154250
X208199Y1145850
X209900Y1093600
X216499Y1053050
X215999Y1039550
X232499Y1038050
X202100Y1028100
X233999Y1012550
X217999Y1012050
X207299Y1008150
X217499Y998550
X233999Y997050
X206299Y990250
X232299Y981950
X217499Y981050
X205999Y978250
X216999Y967550
X233499Y966050
X213999Y958650
X225299Y957650
X206699Y953050
X214999Y948613
X219499
X214999Y944113
X219499Y943813
X203999Y943350
X214999Y939613
X219499
X204699Y929450
X219499Y926613
X214999
X220499Y887550
X215999
X232399Y886550
X215499Y883550
X209000Y846113
X204496Y846111
X208986Y842113
X204649
Y838050
X208999
X217300Y816800
X202900Y811900
X233799Y806350
X208299Y805350
X227199Y795050
X214799Y774750
X234299Y773750
X224099Y770250
X208799Y766750
X209500Y759000
X226399Y677550
X212999Y677350
X218800Y668700
X234200Y668300
X219999Y647050
X207300Y639400
X219999Y632550
X206499Y623550
X224999Y613450
X206499Y609050
X220499Y577550
Y560050
Y545550
X205300Y508100
X224299Y494650
X218499Y474850
X232499Y461550
X231999Y445550
X209999Y426150
X237699Y426050
X232999Y414550
X209499Y412550
X217599Y396450
X223799Y365350
X209199Y365050
X201199Y266750
X235399Y263350
X217999Y250550
X203499
X210999Y221550
X232400Y220700
X227499Y192050
X231999
X227999Y187050
X231999
Y182550
X227999
Y178050
X231999
X206899Y171650
X229099Y161350
X225499Y63550
Y58050
Y52550
Y46550
X199999Y46050
X208499Y45650
X226499Y5050
X206999
X261499Y4550
X278999Y5050
X241999
X247499Y37550
X246999Y46550
X253999Y48050
X264999Y55350
X246999Y56050
X247499Y65050
X261299Y75950
X265299Y96250
X258699Y104550
X244499Y122050
X274700Y131500
X244499Y136550
X244900Y149100
X262299Y164050
X262699Y208550
X271999Y216050
X265999Y245050
X249800Y248800
X267498Y295114
Y300114
Y305114
Y310114
X277799Y338599
X276299Y376050
X258999Y396650
X269999Y415050
X252499
X266699Y425050
X272499Y445050
X251499Y446050
X272999Y461050
X251999Y462050
X266199Y472350
X244199Y483350
X257499Y498050
X242099Y511750
X257499Y512550
Y530050
X244999Y545050
X277999Y545350
X244999Y559550
X256499Y577050
X244999
X256499Y591550
Y609050
X269499Y616550
Y631050
X244499Y632050
X257199Y640050
X245000Y647000
X269499Y648550
X246500Y663300
X268499Y701550
Y706550
Y711550
Y716550
X245599Y773450
X247099Y795050
X268099Y795450
X275299Y806350
X254699Y807650
X245399Y823550
X264499Y829050
X252399Y838250
X264999Y842550
X244099Y857450
X264999Y858450
X245199Y878050
X252899Y886350
X265799Y901850
X245399Y907450
X274299Y912950
X256199Y916250
X243899Y923650
X269599Y923950
X254899Y929250
X267199Y935350
X253499Y938050
X242199Y938750
X264799Y946850
X252499Y948850
X278799Y956150
X263299Y959350
X272999Y965550
X256499Y967050
X244199Y973250
X277599Y975250
X272999Y981050
X254499Y984550
X245899Y995250
X262499Y995850
X274999Y996550
X258999Y1011550
X274999Y1012050
X275099Y1024750
X269999Y1037050
X253499Y1038550
X253999Y1052050
X269999Y1052550
X272999Y1102850
X249499Y1104150
X274900Y1115600
X262499Y1129150
X276299Y1134550
X260349Y1139200
X272499Y1153050
X268499
X263999
X259999Y1152992
X259499Y1161550
X267999
X263499
X271999
X251999Y1184550
X279799Y1191750
X242599Y1198350
X247899Y1208650
X242199Y1210050
X272999Y1214150
X261199Y1227950
X250900Y1248500
X264800Y1261300
X242900Y1263000
X274299Y1276450
X254899Y1289950
X241399Y1303250
X264799Y1313850
X252399Y1326350
X245999Y1339050
X265299Y1339650
X245999Y1358050
X263699Y1359550
X246499Y1370050
X265499Y1376950
X278799Y1386250
X249800Y1388400
X258999Y1396950
X270599Y1408550
X244999Y1412550
X278000Y1422000
X245499Y1424550
X259299Y1438750
X268499Y1453550
X250199Y1473550
X248000Y1482000
X247500Y1499000
X260999Y1503550
X279499Y1510550
X266999Y1512550
X279499Y1515050
X267349Y1518150
Y1522550
X279075Y1525957
X267349Y1527172
X278567Y1529925
X246200Y1617600
X278499Y1621550
X265700Y1635100
X258700Y1645100
X242999Y1658050
X270999Y1660550
X253999Y1676550
X273499Y1694050
X256499Y1710050
X255699Y1722550
X263499Y1734550
X249199Y1743150
X270599Y1748950
X244999Y1755050
X259499Y1760650
X252199Y1793050
X270599Y1801450
X253899Y1813250
X261499Y1825050
X255999Y1855950
X270299Y1867250
X241199Y1867150
X244700Y1878700
X241255Y1896055
X266999Y1915550
Y1920050
Y1924550
Y1929050
Y1933550
X240900Y1979000
X272000Y1987500
X254500
X291499Y1987550
X311500Y1987500
X293999Y1971050
X289499
X305999Y1969550
X289499Y1966550
X293999
X305999Y1964050
X293999Y1962050
X289499Y1961550
X296858Y1956228
X293999Y1933050
X298499Y1932550
X302499
X306999
X281999Y1928550
Y1923550
X302499Y1922050
X281999Y1918550
X305999Y1913050
X314099Y1901250
X313599Y1889250
X308099Y1880550
X313599Y1870250
X295299
X283999Y1856050
X316999Y1855950
X298999
X315499Y1812250
X284299Y1811150
X303999Y1800850
X286599Y1791850
X290699Y1760750
X303499Y1753550
X285499Y1742550
X297099Y1733850
X303999Y1722050
X280499Y1718550
X291099Y1707450
X299999Y1696050
X284300Y1676900
X318499Y1675550
X302399Y1662950
X316799Y1657450
X289000Y1641800
X307000Y1619600
X289998Y1578114
X293998
Y1573614
X289998
X305998Y1569114
X289998
X293998
X286700Y1516100
X312000Y1514600
X296599Y1497150
X312800Y1467400
X304699Y1457550
X286600Y1449700
X313600Y1442700
X300899Y1433350
X285499Y1427550
X312100Y1420700
X285499Y1418550
X303499Y1411250
X285499Y1399550
X301699Y1395750
X313600Y1391300
X301699Y1377950
X312900Y1366900
X286499Y1364050
X298099Y1357250
X286499Y1345050
X311900Y1344900
X297899Y1336150
X286799Y1326450
X311500Y1316300
X300499Y1305350
X281099Y1302850
X295399Y1292950
X312499Y1280350
X304699Y1265850
X283799Y1249250
X310299Y1240050
X300699Y1227350
X311999Y1213850
X286599Y1203750
X315408Y1202663
X300699Y1185150
X291399Y1174150
X313499Y1170150
X304499Y1156650
X283299Y1144850
X307999Y1142050
X317999Y1137550
X316499Y1124550
X290699Y1122650
X299499Y1113550
X283499Y1113050
X282999Y1099550
X299499Y1098050
X312299Y1093550
X304699Y1057050
X317699Y1054650
X299999Y1052350
X318299Y1038750
X303699Y1038050
X287099Y1035050
X289699Y1021750
X306399Y1020750
X298399Y1008150
X287099Y1000150
X304399Y997550
X294699Y989550
X285399Y982950
X306699Y981250
X298099Y977250
X288099Y971250
X307999Y970650
X299399Y965950
X289399Y963350
X290099Y948650
X281099Y943550
X310699
X315199Y925950
X302199Y914650
X287299Y901050
X302499Y899050
X297499Y884050
X281499Y883550
X280999Y870050
X315199Y869450
X297499Y868550
X283599Y857450
X304899Y856150
X313499Y847850
X293899Y843850
X280999Y843050
X300199Y835250
X280999Y827550
X288899Y820550
X318999Y814350
X307999Y803150
X287799Y794850
X307899Y794550
X290999Y767050
X294999
Y762550
X290999
Y758050
X294999
X306999
X314499Y754550
X280999Y717550
X296399Y716950
X280433Y713590
X280999Y705550
X308899Y705150
X298399Y703450
X280999Y701550
X297699Y681850
X307499Y679050
Y661550
X293999Y648050
X307499Y647050
X293999Y630550
X317999Y627850
X293999Y616050
X280999Y608550
X302899Y607950
X280999Y591050
Y576550
X307499Y573050
X296199Y568550
X307499Y555550
X297499Y551050
X307499Y541050
X281999Y529550
X297599Y519350
X309399Y513450
X281999Y512050
X298599Y501250
X281999Y497550
X312499Y484050
X292999Y483550
X306100Y462000
X286999Y462050
X291599Y446150
X300899Y431850
X303999Y415550
X284499Y415050
X310999Y396250
X289399Y395750
X299899Y376650
X289998Y361114
X293998
Y356614
X289998
Y352114
X293998
X305998
X313000Y313900
X316999Y312576
X279998Y308614
Y304114
Y299614
Y295114
X313199Y270350
X283499Y245050
X297999
X310499Y216550
X290999Y216050
X307199Y205550
X317499Y192950
X280999Y152050
X306100Y126500
X280999Y120050
X283599Y106250
X289499Y80550
X307999Y78550
X288499Y76550
X303999Y74050
X289999Y72550
X308499
X290999Y67550
X315799Y55350
X311299Y55450
X306999
X308800Y46400
X304500Y44500
X308700Y39800
X303300Y39500
X289499Y39050
X286603Y34928
X294100Y28000
X310499Y5050
X292999Y4550
X329999Y5050
X345499
X332200Y94200
X345999Y100550
X355999
X350999
X347499Y113050
X351999
X356499
X343399Y161350
X321799Y173950
X354099Y175350
X343999Y190050
X331499Y193250
X343799Y204550
X355499Y219050
X337999
X355999Y242750
X325499Y249450
X343499Y253550
X347699Y269050
X337499Y282550
X354999
X347399Y301950
X359399Y307250
X321748Y343299
X339399Y358050
X357999Y359050
X328799Y372350
X354099Y373050
X338399Y395650
X324999Y414550
X336099Y417550
X354699Y426650
X322099Y426850
X338899Y433850
X328599Y442250
X356399Y451750
X327900Y463200
X351399Y470750
X333499Y483050
X358399Y498650
X329999Y510450
X340799Y512050
X357399Y521250
Y530550
X321999Y533150
X341399Y535850
X331999Y540550
X357399Y543850
X321999Y550550
X331999Y555050
X341399Y558950
X357999Y559450
X321299Y565250
X331999Y572550
X359399Y576050
X320799Y582050
X340299Y586550
X359399Y599650
X328599Y602450
X342199Y613050
X359699Y627550
X328499Y635650
X342099Y646350
X331999Y646550
X358899Y657150
X331999Y661050
X341899Y664950
X359399Y669450
X331999Y678550
X342599Y678850
X359199Y690650
X324599Y696150
X345399Y698950
X357699Y707750
X330799Y712450
X341399Y715050
X355999Y752850
X347699Y773450
X353999Y787750
X338099Y811650
X338599Y821650
X325599Y823950
X338599Y840450
X323799Y859850
X330299Y871850
X323099Y885050
X340099Y887350
X321099Y899650
X338399Y901050
X340099Y910350
X322099Y913650
X331099Y923650
X340399Y931250
X328099Y937250
X340099Y952850
X323499Y956950
X329799Y970650
X333099Y983450
X320999Y997250
X321299Y1012450
X331299Y1017150
X321299Y1024750
X331599Y1028750
X329599Y1040750
Y1057050
X319999Y1066950
X339599Y1081550
X329299Y1098550
X326599Y1112350
X332999Y1123050
Y1138550
X323999Y1153250
X329799Y1182750
X328999Y1200550
X326649Y1218850
Y1227850
X327999Y1255050
X333349Y1270500
Y1288900
Y1307000
Y1332800
X344399Y1338150
X343599Y1360050
X333349Y1363500
Y1393100
X344099Y1393750
Y1421150
X333349Y1429500
X344099Y1449550
X333349Y1481900
X332500Y1519700
X351899Y1570850
X344500Y1583600
X350600Y1610900
X349099Y1634550
X337199Y1636350
X320299Y1642950
X335767Y1662735
X351099Y1691150
X334399Y1691650
X352000Y1700400
X320999Y1706050
X329999Y1716950
X321999Y1733050
X359499Y1736850
X343899Y1752650
X326301Y1766030
X321499Y1772550
X327299Y1791850
X357999Y1796050
X334999Y1797050
X322299Y1802150
X355699Y1810750
X351999Y1855450
X337499Y1855950
X336799Y1869950
X326399Y1876250
X348999Y1879050
X336799Y1888950
X326399Y1895250
X348999Y1898050
X336799Y1897950
X326899Y1907250
X349499Y1910050
X335799Y1916450
X358999Y1925050
X347999Y1925550
Y1944550
X348499Y1956550
X347699Y1972250
X326799Y1977050
X345499Y1987550
X329999
X382499
X364999Y1987050
X399299Y1976750
X385099Y1975950
X367299Y1972950
X388499Y1959550
X367299Y1956950
X388499Y1950550
X367999Y1940250
X388499Y1932950
X369199Y1919750
X389499Y1913050
X359999Y1906550
X389499Y1904050
X369999Y1901950
X359999Y1897550
X389499Y1885050
X369799Y1880050
X359999Y1878550
X369499Y1855950
X391499
X387899Y1802850
X393999Y1784550
X376499Y1775550
X393499Y1759550
X376799Y1734050
X380099Y1709650
X377099Y1696350
X374999Y1656750
X377700Y1629000
X375099Y1608250
X376099Y1572850
X374099Y1554550
X374799Y1491250
X373099Y1456550
X376299Y1437650
X373499Y1430050
Y1421050
Y1402050
X374499Y1375550
Y1366550
Y1347550
X375599Y1323350
X376599Y1293950
X376499Y1264550
Y1255550
Y1236550
X377499Y1210050
Y1201050
Y1182050
X360399Y615550
X368299Y386350
X380599Y381050
X394899Y357750
X386599Y348450
X383299Y310250
X386899Y299250
X369499Y282550
X382999Y276650
X381999Y254050
X362499Y253550
X387599Y220150
X369999Y219050
X385999Y207250
X382499Y190550
X362999Y190050
X389299Y161650
X363999Y153550
X381299Y136750
X363999Y136050
Y121550
X360999Y113050
X380599Y103550
X360999Y100550
X389599Y90950
X376999Y70050
X381499
Y65550
X376999
X369999Y23550
X382499Y20050
X369999Y19050
X380999Y15550
X376499
X371999
X395999Y5550
X382499Y5050
X364999Y4550
X413499Y6050
X432999
X416999Y25050
X436499Y31350
X417499Y46550
X436499Y50350
X416999Y63550
X437499Y71350
X417499Y79050
Y93550
Y108050
X400499Y119550
X417499Y125550
X400499Y134050
X416999Y145050
X400499Y151550
X416999Y164050
X417999Y185050
X430499Y217050
X423799Y259750
X437499Y275050
X412999Y275550
X437499Y289550
X412999Y290050
X437499Y307050
X412999Y307550
X422499Y348150
X422199Y363350
X438999Y381550
X420199Y391350
X426599Y415350
X415099Y422550
X410799Y431150
X419599Y458550
X431099Y479350
X415999Y518550
X435499Y519050
X430099Y551450
X427999Y565550
Y580050
Y597550
X427499Y624550
X420199Y638550
X437299Y744650
X435299Y763150
X424999Y766550
X435299Y777650
X422999Y785050
X435299Y795150
X422999Y799550
X434799Y814650
X422999Y817050
X434799Y833650
X422499Y836550
Y855550
X418799Y877050
Y896050
X423299Y994050
Y1013050
X424299Y1034050
X432599Y1064550
X433599Y1085550
X409499Y1102550
X428999
X419999Y1115550
X439499
X436999Y1128050
Y1142550
X437599Y1150050
X415499Y1161550
Y1176050
X416099Y1183550
X419499Y1219550
Y1234050
X420099Y1241550
X424999Y1259550
Y1278550
X425499Y1290550
X428499Y1325350
X416699Y1342650
X434499Y1360250
X416199Y1367550
X422299Y1394950
X426799Y1416050
X423299Y1430350
X425799Y1447950
X427099Y1469150
X414799Y1532350
X424299Y1541350
X439599Y1552150
X418299Y1561250
X434500Y1579500
X415999Y1603250
X431999Y1605550
X432499Y1617550
X416199Y1625250
X425499Y1635050
X414799Y1653750
X427499Y1662050
X414399Y1678350
X432400Y1680100
X428600Y1691200
X414499Y1707250
X435300Y1715300
X429499Y1748050
X436799Y1772550
X410757Y1772872
X422999Y1778550
X417799Y1790850
X414499Y1810450
X426499Y1855450
X406999Y1855950
X406499Y1874050
X434299Y1876050
X421399Y1888050
X406499Y1893050
X434299Y1895050
Y1904050
X406999Y1905050
X421399Y1907050
Y1916050
X405499Y1920550
X433299Y1922550
X420399Y1934550
X405499Y1939550
X433299Y1941550
Y1950550
X405999Y1951550
X420399Y1953550
Y1962550
X420799Y1977250
X436299
X420500Y1987000
X403500
X438999Y1987550
X456500Y1987500
X476000Y1987000
X473299Y1977250
X455799Y1976750
X459299Y1966850
Y1957850
X445999Y1954550
X475199Y1951950
X445999Y1945550
X475199Y1942950
X459299Y1938850
X445999Y1926550
X475199Y1923950
X460299Y1920350
Y1911350
X446999Y1908050
X476199Y1905450
X446999Y1899050
X476199Y1896450
X460299Y1892350
X446999Y1880050
X476199Y1877450
X443999Y1855950
X464999Y1855450
X448099Y1809450
X445499Y1792550
X472699Y1792150
X463999Y1772050
X441499Y1758050
X458499Y1742050
X468499Y1712550
X448399Y1699450
X467999Y1696050
Y1687050
X447699Y1682850
X467999Y1668050
X449599Y1656950
X460199Y1632850
X472499Y1620550
X443799Y1612250
X472499Y1611550
X465999Y1603450
X449199Y1579050
X472299Y1572050
X452199Y1550650
X474299Y1544750
X461399Y1541650
X444299Y1532650
X466999Y1530650
X459699Y1468050
X478299Y1464850
X445099Y1464250
X456399Y1445950
X441499Y1431550
X459999Y1424050
X441499Y1414050
X464199Y1401450
X441499Y1399550
X466699Y1378150
X444899Y1377950
X468699Y1362850
X473999Y1342450
X448099Y1341250
X468999Y1323950
X465499Y1293550
Y1284550
X443799Y1274250
X465499Y1265550
X443799Y1265250
Y1246250
X443199Y1238750
Y1224250
X474099Y1165550
X454499Y1161550
X473099Y1144550
X453499Y1140550
X454999Y1115550
X474499Y1115050
X444499Y1102550
X463999Y1102050
X463499Y1083850
X462499Y1062850
Y1043850
X461999Y985050
Y966050
X462499Y946550
X443599Y945650
X462499Y929050
X442599Y924650
X462499Y914550
X442599Y905650
X464499Y896050
X462999Y884050
X475699Y880450
X462999Y865050
X479599Y847550
X453399Y826950
Y807950
X468699Y788350
X452099Y781450
X467699Y772750
X452099Y762450
X472999Y736550
X451099Y711650
X463999Y691550
X444799Y687350
X463999Y674050
X450399Y672750
X463999Y659550
X452499Y597050
Y579550
Y565050
X456499Y518050
X453999Y509550
X471499Y493950
X454499Y490050
Y472550
X440099Y459250
X472499Y458050
X454499
X443199Y440850
X454999Y438550
X453999Y417550
X468799Y414250
X450300Y404200
X458499Y382050
X443499Y354050
X464499Y353050
X466399Y304950
X479299Y297250
X463999Y283550
X444499Y283050
X448999Y255550
X469999Y254550
X449999Y217050
X472999Y214550
X446799Y205650
X445799Y184650
X474099Y181050
X445799Y165650
X473099Y160050
X442799Y142450
X473099Y141050
X471399Y124550
X441799Y121450
X470399Y103550
X441799Y102450
X470399Y84550
X466799Y64750
X465799Y43750
Y24750
X448499Y6050
X467999Y5550
X498999Y6050
X485499
X516499Y6550
X499999Y25550
X500499Y47050
X499999Y64050
X500499Y79550
Y94050
Y108550
Y126050
X499999Y145550
Y164550
X483599Y179350
X504199Y193250
X502899Y217150
X488999Y254550
X508499Y255050
X495999Y283550
X481499
X515499Y284050
X516899Y306950
X483499Y353050
X502999Y353550
X485000Y373200
X509999Y382550
X484900Y394700
X490999Y412550
X518999Y416550
X503699Y419250
X490999Y427050
Y444550
X511299Y449150
X490499Y464050
X498399Y470050
X519499Y471550
X490499Y483050
X519499Y489050
X508699Y498950
X491499Y504050
X518999Y508550
X485299Y534550
X514499Y546050
X504499Y566050
X479999Y566550
X504499Y580550
X479999Y581050
X504499Y598050
X479999Y598550
X509999Y640550
Y655050
X488499Y659050
X509999Y672550
X488499Y673550
Y691050
X506599Y711650
X487299Y716950
X490299Y734550
X489599Y752450
X511199Y782050
X495999Y795050
X493999Y813550
X512899Y823550
X493999Y828050
X512899Y842550
X493999Y845550
X493499Y865050
X510899Y868150
X493499Y884050
X506899Y900950
X485799Y901050
Y920050
X506899Y919950
X486799Y941050
X516499Y957050
X514499Y975550
Y990050
X493099Y996350
X514499Y1007550
X494099Y1017350
X513999Y1027050
Y1046050
X483499Y1064850
X484499Y1085850
X481499Y1102550
X501499
X518999Y1103050
X511999Y1115550
X491999
X504399Y1132250
X505399Y1153250
X486499Y1196050
X506599Y1202350
X486499Y1210550
X506599Y1216850
X487099Y1218050
X507199Y1224350
Y1243350
Y1252350
X498299Y1323350
X518499Y1346950
X499199Y1350550
X485599Y1367550
X508599Y1370550
X498899Y1386450
X481499Y1402550
X498899Y1408350
X481499Y1417050
X516999Y1418050
X500899Y1434350
X516999Y1437050
X517499Y1449050
X482599Y1449950
X505899Y1466250
X518899Y1530150
X488299Y1531050
X499699Y1538950
X502199Y1566250
X510100Y1579800
X484200Y1579900
X487099Y1606250
X508199Y1610450
X501399Y1634550
X484999Y1636550
X518499Y1643950
X509199Y1660550
X483599Y1662550
X507399Y1683350
X485599Y1694850
X502899Y1709650
X480999Y1756050
X508200Y1758200
X515499Y1779050
X484999
X496999Y1799550
X481299Y1811150
X514199Y1815750
X499999Y1854950
X517499Y1855450
X480499
X519399Y1876750
X492999Y1878050
X505799Y1893050
X519399Y1895750
X492999Y1897050
X519399Y1904750
X493499Y1909050
X505799Y1912050
Y1921050
X518399Y1923250
X491999Y1924550
X504799Y1939550
X518399Y1942250
X491999Y1943550
X518399Y1951250
X492499Y1955550
X504799Y1958550
Y1967550
X509299Y1977250
X493799
X492500Y1987500
X511999Y1987550
X531500Y1987500
X553499Y1987050
X546299Y1977250
X528799Y1976750
X546999Y1966850
X532499Y1958550
X546999Y1957850
X532499Y1949550
X546999Y1938850
X532499Y1930550
X547999Y1920350
X533499Y1912050
X547999Y1911350
X533499Y1903050
X547999Y1892350
X533499Y1884050
X554499Y1855950
X538999
X531799Y1818450
X555500Y1802700
X526499Y1801150
X539499Y1788150
X544300Y1784638
X532499Y1763050
X522300Y1739200
X556199Y1727050
X538299Y1721050
X555899Y1706750
X532999Y1700550
X555399Y1689350
X532499Y1688550
X555199Y1674750
X532499Y1669550
X532599Y1655650
X554199Y1651950
X532499Y1635550
X553399Y1624550
X529499Y1616550
X528999Y1604550
X552099Y1601950
X552199Y1576650
X533800Y1575500
X529799Y1555050
X538999Y1528350
X546099Y1467550
X528499Y1460250
X557499Y1452050
Y1443050
X536799Y1436350
X557499Y1424050
X538799Y1409750
X523999Y1391050
X540399Y1382150
X523499Y1379050
Y1360050
X545099Y1355250
X559099Y1343250
X555699Y1322950
X549399Y1302850
X530499Y1297050
X549399Y1293850
X527499Y1278150
X549399Y1274850
X548799Y1267350
X525999Y1263050
X548799Y1252850
X525999Y1245550
Y1231050
X547099Y1230750
Y1221750
X527999Y1212550
X547099Y1202750
X527499Y1200550
X546499Y1195250
X527499Y1181550
X546499Y1180750
X529499Y1116050
X548999
X553999Y1103050
X538499
X558499Y1088050
X535599Y1069550
X558499Y1069050
X558999Y1049550
X534599Y1048550
X558999Y1032050
X541899Y1021450
X558999Y1017550
X540899Y1000450
Y981450
X540299Y956850
X539299Y935850
X521999Y914550
Y895550
X522499Y876050
X541399Y873450
Y854450
X526499Y851150
X534499Y805950
X547499Y799050
Y780050
X525499Y772450
X547999Y760550
X527499Y747150
X547999Y743050
Y728550
X549999Y710050
X534499Y672050
Y654550
Y640050
X558699Y624550
X554499
X558709Y620245
X554499Y620050
X558499Y616050
X554304Y615840
X558499Y562550
X538999Y562050
X535499Y545050
X555999Y504550
X539299Y485550
X556499Y485050
Y467550
X539799Y466050
X538799Y445050
X555999Y412550
X530999Y381550
X548100Y362200
X520499Y353550
X558099Y335050
X557933Y331010
X557999Y326550
Y322550
X540099Y306550
X544799Y293950
X536499Y283050
X540499Y255050
X525999
X552999Y217550
X533499
X528799Y199950
X542499Y185050
X541499Y164050
X521299Y162450
X541499Y145050
X520299Y141450
X541999Y125550
X520299Y122450
X541999Y108050
Y93550
X523899Y85350
X541999Y79050
X522899Y64350
X541499Y63550
X541999Y46550
X522899Y45350
X541499Y25050
X535999Y6550
X551499
X570999Y6050
X588499Y6550
X587999Y25050
X588499Y46550
X587999Y63550
X568099Y72550
Y91550
X569099Y112550
X588499Y125550
X562799Y127750
X587999Y145050
X562799Y146750
X587999Y164050
X563799Y167750
X588999Y185050
X565999Y199950
X587999Y217050
X568499Y217550
X572999Y255050
Y269550
Y287050
X572499Y306550
Y325550
X599299Y344650
X573499Y346550
X579899Y375750
X599799Y385150
X592999Y407550
X577399Y420050
X592999Y422050
Y439550
X578399Y441050
X592499Y459050
X577899Y460550
X592499Y478050
X576099Y481850
X593499Y499050
X577099Y502850
X576599Y522350
X579499Y561550
X595999Y609550
Y624050
Y641550
X573499Y658550
Y673050
X597999Y690050
X573499Y690550
X565699Y710650
X586299Y711250
X577999Y732050
X575999Y750550
Y765050
Y782550
X575499Y802050
Y821050
X576499Y842050
X578299Y895650
X562999Y898050
X578299Y914650
X560999Y916550
Y931050
X570899Y946850
X560999Y948550
X583299Y961450
X570899Y965850
X560499Y968050
X583299Y980450
X571899Y986850
X560499Y987050
X560999Y999050
X598999Y1020550
Y1035050
X573499Y1036550
X598999Y1052550
X573499Y1055550
X598499Y1072050
X574499Y1076550
X598499Y1091050
X568499Y1101550
X588499
X598999Y1114550
X578999
X564499Y1116050
X567999Y1187550
X597599Y1196050
X567999Y1206550
X596599Y1215050
X567999Y1215550
X582699Y1233250
X565999Y1234050
X582699Y1247750
X565999Y1248550
X583299Y1255250
X598499Y1261550
X566399Y1273850
X583299Y1274250
X598499Y1280550
X583299Y1283250
X598999Y1292550
X579299Y1300750
X561099Y1301050
X599499Y1351550
X581999Y1370150
X599499Y1370550
X580999Y1412750
X575699Y1438950
X582999Y1461250
X590599Y1483450
X563499Y1486550
Y1492050
Y1497550
Y1503550
X582299Y1534150
X599799Y1544650
X567999Y1549950
X588099Y1572050
X573400Y1577600
X588000Y1604000
X569499Y1610550
Y1619550
X590799Y1627850
X580799Y1646150
X593399Y1668850
X572999Y1675550
X590599Y1694450
X572999Y1694550
Y1703550
X580299Y1722550
X582599Y1740050
X593299Y1760950
X560399Y1792550
X595199Y1820910
X573999Y1855450
X591499Y1855950
X562599Y1874450
X588899Y1882350
X575999Y1888050
X562599Y1893450
X588899Y1901350
X562599Y1902450
X575999Y1907050
X588899Y1910350
X576499Y1919050
X561599Y1920950
X587899Y1928850
X574999Y1934550
X561599Y1939950
X587899Y1947850
X561599Y1948950
X574999Y1953550
X587899Y1956850
X575499Y1965550
X585799Y1976250
X570299
X588499Y1986550
X568999Y1987050
X605999
X626999
X622799Y1976250
X605299Y1975750
X615499Y1968550
X601799Y1961850
X615499Y1959550
X601799Y1952850
X629699Y1947250
X615499Y1940550
X629699Y1938250
X601799Y1933850
X616499Y1922050
X629699Y1919250
X602799Y1915350
X616499Y1913050
X602799Y1906350
X630699Y1900750
X616499Y1894050
X630699Y1891750
X602799Y1887350
X630699Y1872750
X627499Y1855950
X611999
X627494Y1829068
X632799Y1820450
X608599Y1810750
X633837Y1807384
X619499Y1803150
X626999Y1800050
X627273Y1793905
X606999Y1745550
X625499Y1725050
X607599Y1716450
X609499Y1692050
X635099Y1691150
X609499Y1675050
X627299Y1659550
X600599Y1645450
X628499Y1636650
X612499Y1615550
X633499Y1615450
X635500Y1603900
X611999Y1603550
X611900Y1577900
X639200Y1576200
X623499Y1564050
X617699Y1530350
X610899Y1496750
X625199Y1489150
X636799Y1461250
X601299Y1447650
X626799Y1432350
X604899Y1407750
X627499Y1406050
X625499Y1383450
X599999Y1382550
X617899Y1360850
X632499Y1347950
X606199Y1338250
X605599Y1326350
X631799Y1322650
X608899Y1305050
X618199Y1296250
X638999Y1295550
X618199Y1287250
X638999Y1286550
X618199Y1268250
X638999Y1267550
X617599Y1260750
Y1246250
X630499Y1243950
X600899Y1238650
X626199Y1183450
X628699Y1164550
X603899Y1157850
X627699Y1143550
X616499Y1115050
X633999Y1103050
X605999Y1102050
X629499Y1090550
Y1071550
X612399Y1066650
X629999Y1052050
X611399Y1045650
X629999Y1034550
X611399Y1026650
X629999Y1020050
X600999Y1002050
X631999Y1001550
X617699Y988250
X639499Y971150
X616699Y967250
X601499Y954550
X639499Y952150
X616699Y948250
X601499Y937050
Y922550
X603499Y904050
X629499Y868550
X613499Y868050
X612999Y854550
X629499Y853050
X621999Y835050
X606999Y797050
Y778050
X621499Y767150
X607499Y758550
X633499Y750150
X607499Y741050
Y726550
X629099Y714050
X609499Y708050
X622999Y689550
Y672050
X605299Y661750
X631999Y639650
X620499Y623550
Y609050
X625999Y585050
X606499Y584550
X613700Y504600
X621499Y484050
Y466550
Y452050
X621999Y432550
X620999Y411550
X607399Y380250
X635399Y376250
X600299Y365650
X632399Y358750
X628499Y339550
X628200Y320000
X627499Y299550
X627999Y280050
Y262550
Y248050
X605499Y217550
X625499
X623899Y202550
X625499Y183050
X604999Y173750
X624499Y162050
X603999Y152750
X624499Y143050
X603999Y133750
X624999Y123550
X604999Y75350
X624499Y61550
X603999Y54350
X624999Y44550
X603999Y35350
X624499Y23050
X625999Y7050
X608499Y6550
X660999Y7050
X645499
X674999Y20550
X651799Y40650
X675499Y42050
X674999Y59050
X651799Y59650
X675499Y74550
X652799Y80650
X675499Y89050
Y103550
Y121050
X649899Y138350
X674999Y140550
X649899Y157350
X674999Y159550
X650899Y178350
X675999Y180550
X642999Y218050
X677999
X662499
X653999Y286550
X656499Y307050
Y324550
X655999Y344050
X659899Y363250
X643599Y395950
X644599Y416950
X644099Y436450
Y450950
X666999Y476550
Y491050
Y508550
X642499Y525750
X666499Y528050
X643499Y546750
X666499Y547050
X642999Y566250
X667499Y568050
X646999Y584550
X674999Y601550
X640599Y604650
X665999Y623550
X645099Y639150
X673999Y645150
X647499Y657050
X678499Y671050
X647499Y671550
X678499Y688550
X647499Y689050
X648999Y702350
X679299Y703050
X651999Y718350
X647399Y742150
X665499Y766550
X664999Y786050
X653099Y803350
X664999Y805050
X645799Y816650
X665999Y826050
X641599Y843250
X663999Y844550
Y859050
X641599Y862250
X663999Y876550
X642599Y883250
X663499Y896050
Y915050
X664499Y936050
X658999Y959050
X656999Y977550
X678299Y978350
X656999Y992050
X678299Y997350
X656999Y1009550
X673999Y1017550
X656499Y1029050
X673999Y1036550
X656499Y1048050
X674699Y1061450
Y1080450
X669499Y1116550
X674999Y1134950
X641799Y1137650
X667199Y1152850
X650299Y1153150
X668199Y1173850
X651299Y1174150
X650599Y1182050
X670199Y1192750
X651599Y1203050
X671199Y1213750
X668699Y1227650
X657099Y1272850
X657799Y1288450
X672999Y1303450
X656399Y1307050
X671999Y1324950
X665699Y1337250
X677999Y1347550
X654499Y1354050
Y1373050
X654999Y1385050
X652999Y1403550
Y1418050
X678299Y1425050
X652999Y1435550
X659699Y1445950
X665699Y1462250
X656099Y1479550
X672399Y1508750
X673699Y1535350
X643099Y1541350
X662099Y1549650
X652399Y1575850
X670699Y1603150
X652499Y1609550
Y1618550
X671399Y1625350
X649399Y1644950
X657099Y1668850
X674999Y1676550
X656499Y1697050
X642499Y1709050
X675499Y1738050
X665399Y1752350
X675499Y1757050
X675999Y1769050
X650399Y1771250
X659159Y1792278
X642400Y1800100
X644049Y1810834
X659549Y1815384
X640999Y1815550
X669399Y1855350
X667999Y1870950
X645099Y1877550
X661299Y1890050
X674899Y1892350
X676399Y1901150
X645399Y1906150
X661299Y1909050
X674899Y1911350
X661299Y1918050
X674899Y1920350
X646799Y1926450
X644999Y1934050
X660299Y1936550
X673899Y1938850
X644999Y1953050
X660299Y1955550
X673899Y1957850
X660299Y1964550
X645499Y1965050
X673899Y1966850
X678799Y1975750
X643799Y1976250
X659299
X661999Y1986550
X679499Y1987050
X642499
X702499Y1987550
X717999
X696299Y1976250
X685499Y1968050
X709199Y1962950
X685499Y1959050
X698299Y1948050
X711899Y1944050
X685499Y1940050
X695299Y1926450
X716599Y1918450
X696299Y1898850
X705599Y1891850
X686999Y1870250
X690899Y1855850
X706399
X697999Y1844550
X704300Y1828400
X686473Y1818375
X711500Y1817700
X717000Y1812384
X705000Y1811900
X706549Y1793634
X693549Y1793134
X715999Y1772050
X694599Y1768450
X715999Y1763050
X709099Y1751850
X690499Y1744950
X715999Y1744050
X702599Y1730550
X693099Y1722350
X717099Y1702450
X691999Y1660550
X686699Y1638650
X693599Y1602450
X706700Y1579900
X681299Y1579150
X698599Y1568550
X685299Y1551950
X708899Y1549250
X714599Y1533950
X716199Y1503050
X686999Y1468850
X716899Y1459850
X700899Y1450250
X719499Y1446650
X692999Y1421050
Y1406550
X702299Y1404450
X681299Y1393150
X694999Y1388050
X713899Y1386450
X694999Y1379050
X680299Y1365850
X694999Y1360050
X707899Y1346250
X695999Y1323350
X719199Y1322350
X709699Y1264550
X684299Y1249550
X708699Y1243550
X695999Y1235050
Y1217550
X713599Y1214650
X695999Y1203050
X714399Y1199750
X697999Y1184550
X713399Y1178750
X697499Y1172550
X717999Y1169150
X697499Y1153550
X716999Y1148150
X704299Y1132650
X700499Y1118550
X709999Y1105550
X689999
X692499Y1082050
X713499Y1068550
X692499Y1063050
X713999Y1049050
X692999Y1043550
X713999Y1031550
X692999Y1026050
X713999Y1017050
X692999Y1011550
X694999Y993050
X706499Y942550
X688099Y936350
X707399Y918550
X687099Y915350
X707399Y899550
X687099Y896350
X705999Y865550
Y851050
X688099Y844650
X707999Y832550
X687099Y823650
X706999Y811550
X687099Y804650
X706999Y792550
X685999Y780050
X707499Y773050
X694599Y763450
X710899Y751150
X696299Y741850
X716599Y736850
X681899Y713650
X702999Y688050
Y670550
Y656050
X693999Y648150
X717099Y636050
X690499Y623050
X699999Y610050
X691899Y588850
X692399Y569350
X713099Y561550
X691399Y548350
X713599Y542050
X712599Y521050
X695499
X695999Y501550
X713199Y489450
X694999Y480550
X713199Y474950
X713699Y455450
X712699Y434450
X711499Y344550
X683999Y340050
X711999Y325050
X682999Y319050
X711999Y307550
X682999Y300050
X711999Y293050
X680500Y280700
X683499Y263050
X711499Y252550
X683499Y248550
X711999Y218050
X688999Y196550
X700699Y181750
X699699Y160750
Y141750
X695999Y102650
X694999Y81650
Y62650
X697999Y7050
X680499Y6550
X712499Y6050
X749499Y6550
X729999
X725499Y23550
X757499Y44050
X725999Y45050
X751499Y48350
X725499Y62050
X757499Y63050
X725999Y77550
X758499Y84050
X725999Y92050
Y106550
X752099Y112150
X725999Y124050
X738199Y137450
X725499Y143550
X757999Y154550
X753999
Y159050
X757999
X725499Y162550
X726499Y183550
X728899Y204550
X729499Y218550
X749499
X723200Y275500
X751539Y313984
X755499Y314550
X751499Y318050
X755346Y319149
X749899Y398550
X750899Y419550
X750399Y439050
Y453550
X737999Y467050
X738999Y488050
X755199Y488150
X738499Y507550
X756199Y509150
X738499Y522050
X755699Y528650
X738499Y539550
X737999Y559050
X754499Y564650
X731499Y572050
X755499Y585650
X731499Y586550
Y604050
X754999Y605150
X721499Y617550
X744999Y626550
X729699Y640350
X723499Y654850
X747999Y670750
X751499Y679148
X757400Y686300
X739399Y688150
X754999Y694050
X749999Y700050
X720899Y712250
X727099Y715050
X744999Y715550
X749499Y716050
X745499Y720050
X749999
X732499Y729250
X733799Y761450
X749799Y767450
X723999Y783350
X743099Y785350
X723999Y802350
X751999Y817050
X724999Y823350
X751499Y836550
X728499Y841850
X751499Y855550
X729999Y862850
Y881850
X751599Y887350
X730999Y902850
X751599Y906350
X752599Y927350
X723699Y936250
X749999Y946550
X723699Y955250
X749999Y965550
X724699Y976250
X750999Y986550
X751399Y1004550
Y1023550
X734999Y1030550
Y1045050
X752399Y1052550
X734999Y1062550
X753999Y1100050
X727499Y1106050
X748499Y1111550
X748999Y1115550
X720499Y1118550
X755499Y1119050
X737999
X749999Y1119550
X727499Y1132650
X737999Y1159550
X758799Y1171150
X737999Y1178550
Y1187550
X758799Y1190150
Y1199150
X735999Y1206050
X756799Y1217650
X735999Y1220550
X725499Y1231650
X756799Y1232150
X757399Y1239650
X725499Y1250650
X740499Y1252550
X757399Y1258650
X725499Y1259650
X757399Y1267650
X740499Y1270050
X723499Y1278150
X755399Y1286150
X723499Y1292650
X740799Y1298750
X755399Y1300650
X742099Y1320650
X739199Y1348950
X734199Y1373850
X736199Y1399050
X721899Y1419050
X754999Y1420050
X737799Y1428350
X754999Y1437550
X741099Y1450250
X729199Y1492750
X741099Y1498150
X755499Y1507550
X747199Y1509150
X751000Y1517000
Y1521000
X757500Y1522500
X751000Y1525000
X735799Y1533650
X734499Y1563550
X722199Y1564250
X755499Y1568550
X743400Y1578700
X751300Y1604900
X719999Y1605050
X732999Y1620050
X738799Y1677250
X756299Y1679050
X727399Y1694350
X750099Y1694950
X756499Y1712150
X739199Y1716750
X721199Y1723750
X747499Y1734350
X751899Y1752150
X729999Y1756450
X756900Y1766000
X752900
X747799Y1766750
X753558Y1769946
X757518Y1770517
X755999Y1775550
X751999
X729499Y1778750
X752657Y1779496
X756617Y1780067
X744049Y1791634
X753949Y1798194
X740549Y1802634
Y1810384
X747599Y1844250
X728099Y1844750
X725899Y1855350
X743399Y1855850
X723199Y1867950
X744699Y1868450
X758399Y1868350
X732999Y1868550
X732199Y1878750
X753699Y1879250
X728299Y1888850
X743799
X755299Y1902150
X739799
X728799Y1908150
X755500Y1914500
X736799Y1919450
X728799Y1933050
X730499Y1954650
X746499Y1974250
X721499Y1974550
X737499Y1987050
X754999Y1987550
X792999
X777499
X789299Y1983850
X771814Y1975713
X784016Y1975708
X775814Y1975699
X783814Y1971713
X770814
X783814Y1967213
X768999Y1930050
X774499
X773999Y1923550
X767999Y1923050
X795499Y1922050
X795501Y1917696
X768499Y1917550
X775999Y1916050
X795493Y1913696
X790499Y1913050
X795526Y1909696
X774499Y1908050
X765999
X783499Y1907050
X780799Y1888850
X763299Y1888350
X769199Y1879250
X788699Y1878750
X797199Y1868450
X779699Y1867950
X791799Y1855850
X779399
X763899
X765099Y1844750
X785599
X767159Y1792364
X787900Y1758800
X765600Y1756800
X779899Y1748150
X794499Y1734550
X770099Y1730350
X779999Y1717050
X770399Y1699650
X783499Y1699050
X782999Y1687050
Y1668050
X765099Y1664950
X776999Y1647650
X797299Y1646650
X768500Y1577500
X778327Y1569796
X782827
X773827
X785827Y1565796
X773327
X785827Y1561296
X795999Y1518550
Y1514050
Y1509550
X769499Y1509050
X773499
X786999Y1506550
X795999Y1504550
X780499Y1500050
X770999
X786500Y1488600
X779000Y1488400
X769300Y1488100
X771399Y1474550
X781999Y1434650
X763399Y1401450
X773999Y1393450
X779399Y1361850
X762499Y1353050
X798299Y1344250
X762499Y1335550
X795299Y1326650
X791999Y1294450
X788999Y1278150
X789499Y1257050
Y1239550
Y1225050
X791499Y1206550
X790999Y1194550
Y1175550
X771333Y1165892
X780333
X775833
X783333Y1161892
X771333
X783333Y1157392
X769499Y1105050
X773499
X769499Y1101050
X773499
X789499Y1099550
X798499Y1097566
X783999Y1096550
X760999Y1095550
X777899Y1028050
X776899Y1007050
Y988050
X773199Y960650
X772199Y939650
Y920650
X776199Y879250
X775199Y858250
Y839250
X778999Y806950
X763099Y796350
X775696Y764382
X771196
X780196
X799385Y761436
X771196Y760382
X783196
Y755882
X794331Y711853
Y707353
X766499Y705550
X794331Y702853
X782999Y699550
X766499Y699050
X794331Y698353
X771800Y686600
X798000Y686400
X786500Y686100
X777499Y664550
X794999
X764599Y655750
X785499Y641050
X777499Y638050
X789999Y602050
Y584550
Y570050
X775499Y553550
X774499Y532550
Y513550
X774999Y494050
Y476550
Y462050
X772478Y363924
X776978
X781478
X772478Y359924
X784478
Y355424
X796873Y307571
Y303071
Y298571
Y294071
X786499Y219050
X766999
X779399Y200550
X797999Y187050
X760799Y181950
X796999Y166050
Y147050
X767399Y140150
X797499Y127550
X796599Y123450
X797499Y110050
X778399Y105250
X797499Y95550
Y81050
X775399Y80250
X796999Y65550
X774399Y54050
X797499Y48550
X796999Y27050
X763399Y24150
X764999Y6550
X784499Y6050
X818999
X801999Y6550
X836499
X824899Y25150
X817599Y43750
X813299Y49350
Y68350
X838999Y85050
X814299Y89350
X837999Y91050
X838499Y99550
Y107050
X813299Y110850
X839499Y119050
X805899Y126150
X821199Y137450
X837499Y138550
X838499Y145050
X800999Y216550
X809373Y292571
Y297571
X808999Y303050
X809373Y307571
X838999Y313550
X821499Y314050
X838499Y352050
X839299Y390950
X819299Y394250
X839299Y409950
X819299Y413250
X820299Y434250
X802999Y466050
X803999Y487050
X824899Y500450
X803499Y506550
Y521050
X825899Y521450
X803499Y538550
X825399Y540950
X834599Y543050
X802999Y558050
X835599Y564050
X814499Y569550
X835099Y583550
X814499Y584050
Y601550
X806300Y670600
X809700Y686300
X806999Y697050
X806831Y701853
Y706853
Y711853
X836149Y714050
X837799Y754150
X835999Y767050
X811499Y767550
X835999Y781550
X811499Y782050
X835999Y799050
X811499Y799550
X802499Y814550
X801999Y834050
X825199Y850850
X801999Y853050
X827699Y873450
X802999Y874050
X827699Y892450
X800999Y892550
Y907050
X828699Y913450
X800999Y924550
X800499Y944050
Y963050
X826999Y963150
Y982150
X801499Y984050
X827999Y1003150
X800999Y1005550
Y1020050
Y1037550
X811499Y1097050
X807499
X802499Y1097566
X807341Y1101216
X806999Y1106050
X807341Y1111216
Y1116216
X836149Y1118550
X808299Y1175850
X831499Y1181550
X806599Y1189750
X831499Y1200550
Y1209550
X803599Y1211050
X829499Y1228050
X810199Y1229350
X829499Y1242550
X810199Y1248350
Y1257350
X828199Y1267850
X808199Y1275850
Y1290350
X826199Y1294450
X831499Y1324950
X822199Y1335250
X799999Y1340550
X819199Y1353550
X799999Y1358050
X825500Y1379000
X806499Y1390550
X834499Y1397550
X806499Y1408050
X836600Y1416500
X803299Y1426650
X805899Y1464250
X801300Y1489000
X809245Y1503722
Y1508722
X808999Y1513550
X809245Y1518722
X839499Y1523550
X839899Y1562050
X825999Y1578050
X813300Y1604100
X826499Y1609050
X803599Y1618350
X827199Y1622750
X814599Y1642650
X837199Y1660550
X802899Y1670550
X823499Y1674050
X839199Y1683550
X823499Y1693050
X808899Y1698450
X823499Y1702050
X829200Y1719800
X824100Y1719900
X819400Y1721900
X819200Y1727100
X808299Y1755250
X827999Y1791550
X801099Y1844750
X829799Y1856350
X809299
X833199Y1868450
X818900Y1870800
X833100Y1878500
X806199Y1879250
X807936Y1910365
Y1914865
X808005Y1918865
X807997Y1922865
X838999Y1928550
X813599Y1979950
X829499Y1980250
X812499Y1987050
X829999Y1987550
X864999Y1987050
X849499
X868699Y1983250
X850499Y1977950
X879399Y1974550
X840999Y1970550
X849999
X856999Y1970050
X865200Y1968000
X873399Y1963650
X864414Y1940050
X861414Y1928550
X843999
X842199Y1879250
X869999Y1855972
X871836Y1840972
X869634Y1826876
X862499Y1823550
X854977Y1818994
X863099Y1813150
X842500Y1799000
X879399Y1798150
X853799Y1790850
X844499Y1788050
X866699Y1770950
X872950Y1744401
X875900Y1709500
X879900Y1709300
X855350Y1703201
X842799Y1701150
X879200Y1698700
X864099Y1683550
X855799Y1658250
X877699Y1646650
X841499Y1638950
X868099Y1635650
X852499Y1621350
X866499Y1612050
X849900Y1605100
X866499Y1603050
X864000Y1578200
X873099Y1572550
X850099Y1572250
X850499Y1562050
X858400Y1561900
X865300Y1557700
X843999Y1523550
X861999Y1522550
X879727Y1463696
X871836Y1450460
Y1435460
Y1420460
X868499Y1410050
Y1392550
X841999Y1358550
X873499Y1356050
X841999Y1341050
X875399Y1322650
X850499Y1300050
X860099Y1295450
X871399Y1291450
X850499Y1282550
X872099Y1268150
X850499Y1268050
X852499Y1249550
X869399Y1243850
X851999Y1237550
X869399Y1229350
X851999Y1218550
X871399Y1210850
Y1201850
X849799Y1199750
X845799Y1190450
X871399Y1182850
X846499Y1170450
X848999Y1158050
X856400Y1157700
X839999Y1157550
X863300Y1153800
X859999Y1118550
X841999
X870298Y1045227
X870468Y1030227
X870777Y1014948
X851999Y983550
X850999Y962550
Y943550
X867199Y941350
X866199Y920350
Y901350
X857099Y873450
X873999Y862550
Y845050
Y830550
X847799Y828250
X859999Y799550
Y782050
Y767550
X846799Y754150
X856299Y753150
X865000Y752100
X866499Y724550
X871385Y719436
X859999Y713050
X871786Y709482
X871499Y689436
X871786Y679436
X860796Y678632
X841000Y671100
X870719Y639705
X870773Y624705
X870719Y609705
X860499Y607550
X861800Y591200
X860699Y565550
X861199Y546050
X860199Y525050
X854999Y464550
X853999Y443550
X840299Y430950
X876799Y426250
X853999Y424550
X875799Y405250
X854499Y405050
Y387550
X875799Y386250
X854499Y373050
X847999Y352550
X858400Y352300
X870600Y346700
X863999Y313550
X879878Y247724
X871786Y233924
Y218924
Y203924
X871499Y146050
X849999Y145550
X872499Y133050
X853999Y132550
X865499Y125550
X875499
X845999Y111050
X843499Y82550
X876999Y82050
X855499
X867499
X841499Y71550
X856499Y71050
X866999Y70550
X840999Y62550
X840499Y55050
X839999Y46050
X865499Y39550
X854499
X860799Y24150
X844799Y19850
X871499Y6550
X855999
X890999Y6050
X908499Y6550
X885999Y21150
X909499Y21550
X917499
X902999Y22050
X902499Y35050
X909999Y35550
X916499Y36050
X883999Y39050
X905499Y56550
X904999Y61550
Y67550
X881499Y70550
X904499Y74050
X886499Y99550
X890459Y100116
X886499Y104550
X890499
X889999Y132550
X891999Y146050
X906999Y224150
X887400Y233555
X906999Y243150
X887400Y259700
X907999Y264150
X906399Y295250
Y314250
X907399Y335250
X904999Y370550
Y385050
Y402550
X904499Y422050
Y441050
X884399Y443450
X905499Y462050
X884399Y462450
X885399Y483450
X913699Y484650
Y503650
X914699Y524650
X903999Y574378
X898999Y604550
Y622050
X918999Y641550
X894000Y642400
X881125Y652050
X900999Y652550
X918999Y656050
X887401Y665000
X900999Y670050
X918999Y673550
X918499Y693050
X895999Y702550
X918499Y712050
X895999Y720050
X919499Y733050
X884499Y767050
Y781550
Y799050
X898499Y830050
Y844550
Y862050
X889699Y876050
X919899Y906350
X886999Y907350
X919899Y925350
X886999Y947250
X886919Y1044478
X880033Y1058592
X887400Y1070600
X897299Y1182450
X887999Y1209350
X892499Y1224550
Y1243550
Y1252550
X890499Y1271050
Y1285550
X890999Y1336550
Y1354050
X894499Y1423550
Y1441050
X886913Y1449010
X887499Y1476050
X895499Y1488050
X902759Y1509585
X914599Y1521650
X894499Y1522050
Y1539550
X910899Y1549250
X909700Y1576400
X907500Y1604000
X886900Y1604100
X887299Y1620050
X908899Y1630050
X914899Y1657550
X895999Y1661250
X882999Y1678250
X903599Y1686850
X883900Y1709500
X902900Y1709800
X893200Y1721300
Y1730000
X886900Y1737900
X882700Y1738300
X904814Y1789113
X911299Y1800850
X903299Y1814750
X894999Y1829050
X905299Y1852650
X887499Y1855550
X914999Y1868050
X894000Y1868452
X900299Y1876950
X887401Y1881500
X914999Y1887050
X915499Y1899050
X897299Y1904150
X914899Y1912450
X907599Y1930050
X897599Y1938750
X916599Y1942650
X904299Y1954950
X914899Y1972250
X884499Y1986550
X901999Y1987050
X936999Y1986550
X921499
X956499Y1986050
X930199Y1979550
X953799Y1977950
X946199Y1966650
X931499Y1962050
X955799Y1951950
X930999Y1950050
X945199Y1946350
X947499Y1936050
X930999Y1931050
X938199Y1917150
X954099Y1915450
X955499Y1902050
X937499Y1893850
X955499Y1893050
X937199Y1869950
X922899Y1853650
X928000Y1818500
X932199Y1801850
X934200Y1793500
X941800Y1787700
X954499Y1783550
X941499Y1776250
X949799Y1756250
X958799Y1715750
X931499Y1702050
X955499Y1690850
X922599Y1682150
X941499Y1679550
X940499Y1656950
X957799Y1646950
X923599Y1634350
X944499Y1632650
X950100Y1626100
X925599Y1612050
X933199Y1577550
X925499Y1562550
X924499Y1541550
X943199Y1531650
X924499Y1522550
X944000Y1511300
X951349Y1504800
X924999Y1503050
X951349Y1500300
X951500Y1495300
X958500Y1486800
X924999Y1485550
X958800Y1481500
Y1477000
Y1472500
X924999Y1471050
X952300Y1467500
X952500Y1462300
Y1457800
X926499Y1456550
X952500Y1452800
Y1448300
X952800Y1442000
Y1437500
X925499Y1435550
X946700Y1426500
X925499Y1416550
X925999Y1397050
X944000Y1391900
X943799Y1380850
X925999Y1379550
Y1365050
X952499Y1361850
X943799Y1342950
X928499Y1325350
X951699Y1302750
X926499Y1298550
X950699Y1281750
X925499Y1277550
X950699Y1262750
X925499Y1258550
X951199Y1243250
X925999Y1239050
X951199Y1225750
X925999Y1221550
X951199Y1211250
X925999Y1207050
X951199Y1199250
X925999Y1195050
X950199Y1178250
X924999Y1174050
X950199Y1159250
X924999Y1155050
X950699Y1139750
X925499Y1135550
X950699Y1122250
X925499Y1118050
X950699Y1107750
X925499Y1103550
X921999Y1090550
X949799Y1080950
X920999Y1069550
X949799Y1068950
X920999Y1050550
X948799Y1047950
X921499Y1031050
X948799Y1028950
X921499Y1013550
X949299Y1009450
X921499Y999050
X949299Y991950
Y977450
X920899Y946350
X943499Y937050
X942499Y916050
Y897050
X920399Y886850
X942999Y877550
X920399Y869350
X942999Y860050
X920399Y854850
X942999Y845550
X922399Y836350
X944999Y827050
X921399Y815350
X943999Y806050
X921399Y796350
X943999Y787050
X921899Y776850
X944499Y767550
X921899Y759350
X944499Y750050
X921899Y744850
X944499Y735550
X950799Y691150
X949799Y670150
Y651150
X950299Y631650
X935999Y616050
X950299Y614150
Y599650
X934999Y595050
X952299Y581150
X934999Y576050
X951299Y560150
X935499Y556550
X951299Y541150
X935499Y539050
Y524550
X951799Y521650
X933999Y506550
X951799Y504150
Y489650
X932999Y485550
Y466550
X954799Y451650
X933499Y447050
X954799Y434150
X933499Y429550
X954799Y419650
X933499Y415050
X953299Y401650
X933999Y395550
X952299Y380650
X932999Y374550
X952299Y361650
X932999Y355550
X952799Y342150
X933499Y336050
X952799Y324650
X933499Y318550
X952799Y310150
X933499Y304050
X953299Y290650
X932999Y283050
X952299Y269650
X931999Y262050
X952299Y250650
X931999Y243050
X952799Y231150
X932499Y223550
X952799Y213650
X932499Y206050
X952799Y199150
X932499Y191550
X956099Y181350
X958799Y167350
X939199Y142050
X943499Y78050
Y72550
X942999Y66550
X928999Y65550
X942999Y61550
X928499Y60550
X928999Y56050
X943499Y55050
X920900Y54700
X928499Y51550
X943499Y48050
X945499Y33550
X940499Y33050
X929999Y32550
X954799Y17850
X941499Y6550
X923999Y6050
X995999
X976499Y6550
X960999
X974699Y21450
X991399Y22450
X977399Y44050
X965999Y47050
Y56050
X991999
X965999Y64050
X974699Y64650
X966499Y73050
Y82050
X983099Y83650
X994399Y101250
X977699Y109150
X981099Y123450
X968399Y137150
X988699Y174350
X967399Y180350
X982999Y189050
Y203550
Y221050
X982499Y240550
Y259550
X983499Y280550
X983999Y301550
Y316050
Y333550
X983499Y353050
Y372050
X984499Y393050
X983999Y412550
Y427050
Y444550
X983499Y464050
X966199Y473350
X983499Y483050
X966199Y492350
X984499Y504050
X967199Y513350
X985999Y522050
Y536550
Y554050
X966799Y566350
X985499Y573550
X966799Y585350
X985499Y592550
X967799Y606350
X986499Y613550
X969499Y639050
Y653550
Y671050
X968999Y690550
Y709550
X969999Y730550
X994999Y733050
X969999Y744250
X994999Y747550
X969999Y758750
X994999Y765050
X969999Y776250
X994499Y784550
X969499Y795750
X994499Y803550
X969499Y814750
X995499Y824550
X970499Y835750
X993499Y843050
X970499Y847750
X993499Y857550
X970499Y862250
X993499Y875050
X970499Y879750
X992999Y894550
X969999Y899250
X992999Y913550
X969999Y918250
X993999Y934550
X970999Y939250
X994499Y941550
Y956050
Y973550
X993999Y993050
X971999Y996550
Y1011050
X993999Y1012050
X971999Y1028550
X994999Y1033050
Y1045050
X971499Y1048050
Y1067050
X972499Y1088050
X998599Y1096450
X975999Y1101050
X998599Y1110950
X975999Y1115550
X998599Y1128450
X975999Y1133050
X998099Y1147950
X975499Y1152550
X998099Y1166950
X975499Y1171550
X999099Y1187950
X976499Y1192550
X999099Y1199950
X976499Y1204550
X999099Y1214450
X976499Y1219050
X999099Y1231950
X976499Y1236550
X998599Y1251450
X975999Y1256050
X998599Y1270450
X975999Y1275050
X999599Y1291450
X976999Y1296050
X965099Y1324350
X996500Y1324800
X975100Y1342600
X976499Y1362550
Y1377050
X992500Y1397300
X964400Y1409700
X994200Y1421500
X962500Y1436500
X972000Y1437500
X962500Y1441000
X972000Y1442000
X962200Y1447300
X971700Y1448300
X962200Y1451800
X971700Y1452800
X962200Y1456800
X971700Y1457800
X962200Y1461300
X971700Y1462300
X962000Y1466500
X971500Y1467500
X973500Y1474000
X966000Y1475000
X973500Y1478500
X966000Y1479500
X973500Y1483000
X966000Y1484000
X973200Y1488300
X965700Y1489300
X960200Y1495300
X972700Y1497300
X960049Y1500300
X972549Y1502300
X960049Y1504800
X972549Y1506800
X962100Y1516000
X973200Y1516400
X967300
X961900Y1522400
X973000Y1522800
X967100
X961400Y1528700
X972500Y1529100
X966600
X961600Y1534400
X966800Y1534800
X972700
X961400Y1540800
X966600Y1541200
X972500
X960900Y1547100
X972000Y1547500
X966100
X961600Y1552900
X972700Y1553300
X966800
X961400Y1559300
X972500Y1559700
X966600
X960900Y1565600
X966100Y1566000
X972000
X961900Y1572400
X973000Y1572800
X967100
X961700Y1578800
X966900Y1579200
X972800
X961200Y1585100
X966400Y1585500
X972300
X961300Y1591600
X972400Y1592000
X966500
X961100Y1598000
X972200Y1598400
X966300
X960600Y1604300
X965800Y1604700
X971700
X989999Y1718050
X993299Y1734350
X965349Y1742000
X994999Y1748950
X976600Y1757100
X976399Y1772250
Y1791150
X971000Y1803000
X993499Y1805550
Y1824550
Y1833550
X995699Y1858950
X971500Y1871500
X966799Y1892150
X974699Y1914450
X991999Y1915750
X992299Y1929050
X980999Y1933350
X971499Y1937050
X987999Y1949050
X971499Y1956050
X989999Y1962650
X971499Y1965050
X987999Y1971950
X994999Y1986550
X973999
X1017999Y1987050
X1005000Y1980500
X1023000Y1973000
X1017499Y1954550
X1002500Y1953500
X1000999Y1946350
X1017999Y1937050
X1001599Y1921450
X1020999Y1912550
Y1897050
X1020499Y1877550
X1011299Y1860650
X1020999Y1860050
X1003599Y1846650
X1022999Y1837050
Y1821550
X1007599Y1818450
X1022499Y1802050
X1009999Y1797450
X1022999Y1784550
X999999Y1775250
X1026899Y1768550
X1015299Y1765950
X1020299Y1746650
X1016899Y1731650
X1008599Y1716050
X1022299Y1715750
X1008999Y1702450
X1024300Y1393600
Y1365200
X1000700Y1358100
X1023300Y1344400
X1022599Y1322950
X1016499Y1301050
X1016999Y1271550
Y1256050
X1016499Y1236550
X1016999Y1219050
X1019499Y1198550
Y1183050
X1018999Y1163550
X1019499Y1146050
X1020499Y1134050
Y1118550
X1019999Y1099050
X1020499Y1081550
X1019999Y1058550
Y1043050
X1019499Y1023550
X1019999Y1006050
Y986550
Y971050
X1019499Y951550
X1019999Y934050
Y917550
X1020499Y900050
Y880550
Y865050
X1019999Y845550
X1020499Y828050
Y809550
X1020999Y792050
Y772550
Y757050
X1020499Y737550
X1020999Y720050
X1020499Y695050
X1020999Y677550
Y658050
Y642550
X1005999Y636350
X1020499Y623050
X1005999Y618850
X1020999Y605550
X1005999Y604350
X1004499Y586350
X1021499Y576050
X1003499Y565350
X1021999Y558550
X1003499Y546350
X1021999Y539050
X1003999Y526850
X1021999Y523550
X1021499Y504050
X1001699Y503350
X1021999Y486550
X1000699Y482350
X1020499Y463550
X1000699Y463350
X1020999Y446050
X1007299Y432450
X1020999Y426550
X1007299Y414950
X1020999Y411050
X1007299Y400450
X1020499Y391550
X1005799Y382450
X1020999Y374050
X1004799Y361450
Y342450
X1020499Y341550
X1020999Y324050
X1005299Y322950
Y305450
X1020999Y304550
X1005299Y290950
X1020999Y289050
X1005799Y271450
X1020499Y269550
X1020999Y252050
X1004799Y250450
Y231450
X1020999Y230550
X1021499Y213050
X1005299Y211950
Y194450
X1021499Y193550
X1005299Y179950
X1021499Y178050
X1020999Y158550
X1021499Y141050
X1020499Y122550
X1010599Y115550
X1020999Y105050
Y85550
X1005299Y71350
X1020999Y70050
X1020499Y50550
X1002699Y40050
X1020999Y33050
X1022000Y15500
X1013499Y6550
T03
X994098Y149588
X271657Y267699
X29531Y309549
X271657Y673210
X994098
Y1068880
X271657Y1078722
X29531Y1029510
X271657Y1484234
Y1889746
X17720Y1903132
T04
X129921Y17716
X994093Y1889751
T05
X78150Y28858
Y178464
Y434370
Y583976
Y839882
Y989488
Y1245394
Y1395000
Y1650906
Y1800512
X158071Y1963268
Y1813662
Y1557756
Y1408150
Y1152244
Y1002638
Y746732
Y597126
Y341220
Y191614
X886417
Y341220
Y597126
Y746732
Y1002638
Y1152244
Y1408150
Y1557756
Y1813662
Y1963268
T06
X-38436Y23633
X-36811Y1104775
X-35919Y1969497
X1075940Y1769358
X1072493Y21507
T07
X9843Y353144
Y717711
Y762617
Y875216
Y1337396
Y1701963
Y1746869
Y1859468
T08
X1019291Y1416024
Y1694212
M30
